FILE_TYPE = MACRO_DRAWING;
SET COLOR_WIRE YELLOW;
SET COLOR_PROP MONO;
SET COLOR_DOT WHITE;
SET COLOR_ARC YELLOW;
SET COLOR_BODY GREEN;
SET COLOR_NOTE MONO;
SET PROP_DISPLAY VALUE;
SET PAGE_NUMBER P95;
FORCEADD GND..1
(-3100 425);
FORCEPROP 3 LASTPIN (-3100 475) SIG_NAME GND\g
J 0
(-3090 485);
DISPLAY 0.659574 (-3090 485);
PAINT MONO (-3090 485);
DISPLAY INVISIBLE (-3090 485);
FORCEPROP 1 LAST VOLTAGE 0
J 0
(-3100 425);
PAINT SKYBLUE (-3100 425);
DISPLAY INVISIBLE (-3100 425);
FORCEPROP 2 LAST CDS_LIB mstr_symbols
J 1
(-3100 425);
PAINT ORANGE (-3100 425);
DISPLAY INVISIBLE (-3100 425);
FORCEPROP 1 LAST SIZE 1B
J 0
(-3025 375);
DISPLAY 1.170213 (-3025 375);
PAINT GREEN (-3025 375);
DISPLAY INVISIBLE (-3025 375);
FORCEPROP 1 LAST BODY_TYPE PLUMBING
J 0
(-3145 382);
DISPLAY 0.340426 (-3145 382);
PAINT GREEN (-3145 382);
DISPLAY INVISIBLE (-3145 382);
FORCEPROP 1 LAST PATH I1
J 0
(-3025 425);
DISPLAY 0.872340 (-3025 425);
PAINT AQUA (-3025 425);
DISPLAY INVISIBLE (-3025 425);
FORCEPROP 1 LAST HDL_POWER GND
J 0
(-3100 575);
DISPLAY 1.170213 (-3100 575);
PAINT GREEN (-3100 575);
DISPLAY INVISIBLE (-3100 575);
FORCEADD FET_N..8
(2150 1350);
FORCEPROP 1 LAST LOCATION Q7E4
J 0
(2350 1350);
DISPLAY 0.617021 (2350 1350);
PAINT AQUA (2350 1350);
FORCEPROP 1 LAST PART_NUMBER C79254-001
J 0
(2350 1150);
DISPLAY 0.617021 (2350 1150);
PAINT BLUE (2350 1150);
FORCEPROP 1 LAST VALUE 2N7002
J 0
(2350 1300);
DISPLAY 0.617021 (2350 1300);
PAINT SKYBLUE (2350 1300);
FORCEPROP 1 LAST MATERIAL FET
J 0
(2350 1250);
DISPLAY 0.617021 (2350 1250);
PAINT SKYBLUE (2350 1250);
FORCEPROP 1 LASTPIN (2150 1150) $PN 2
J 2
(2208 1150);
DISPLAY 0.617021 (2208 1150);
PAINT WHITE (2208 1150);
FORCEPROP 1 LASTPIN (1950 1250) $PN 1
J 2
(1953 1265);
DISPLAY 0.617021 (1953 1265);
PAINT WHITE (1953 1265);
FORCEPROP 1 LASTPIN (2150 1550) $PN 3
J 2
(2203 1515);
DISPLAY 0.617021 (2203 1515);
PAINT WHITE (2203 1515);
FORCEPROP 1 LAST PACK_TYPE SOT23
J 0
(2350 1200);
DISPLAY 0.978723 (2350 1200);
PAINT SKYBLUE (2350 1200);
DISPLAY INVISIBLE (2350 1200);
FORCEPROP 2 LAST CDS_LIB mstr_discrete
J 0
(2150 1350);
PAINT MONO (2150 1350);
DISPLAY INVISIBLE (2150 1350);
FORCEPROP 2 LAST SEC_TYPE SOT23
J 0
(2350 1450);
DISPLAY 1.021277 (2350 1450);
PAINT ORANGE (2350 1450);
DISPLAY INVISIBLE (2350 1450);
FORCEPROP 2 LAST SEC 1
J 0
(2350 1450);
DISPLAY 0.680851 (2350 1450);
PAINT MONO (2350 1450);
DISPLAY INVISIBLE (2350 1450);
FORCEPROP 2 LAST CDS_LOCATION Q7E4
J 0
(2350 1350);
DISPLAY 0.617021 (2350 1350);
PAINT AQUA (2350 1350);
DISPLAY INVISIBLE (2350 1350);
FORCEPROP 1 LAST PATH I104
J 0
(2350 1400);
DISPLAY 0.978723 (2350 1400);
PAINT BLUE (2350 1400);
DISPLAY INVISIBLE (2350 1400);
FORCEPROP 0 LAST ROOM PROC_SIDEBAND
J 0
(2350 1450);
DISPLAY 1.021277 (2350 1450);
PAINT ORANGE (2350 1450);
DISPLAY INVISIBLE (2350 1450);
FORCEADD GND..1
(2150 950);
FORCEPROP 3 LASTPIN (2150 1000) SIG_NAME GND\g
J 0
(2160 1010);
DISPLAY 0.659574 (2160 1010);
PAINT MONO (2160 1010);
DISPLAY INVISIBLE (2160 1010);
FORCEPROP 1 LAST VOLTAGE 0.0V
J 0
(2105 907);
DISPLAY 0.340426 (2105 907);
PAINT SKYBLUE (2105 907);
DISPLAY INVISIBLE (2105 907);
FORCEPROP 2 LAST CDS_LIB mstr_symbols
J 0
(2150 950);
PAINT MONO (2150 950);
DISPLAY INVISIBLE (2150 950);
FORCEPROP 1 LAST SIZE 1B
J 0
(2225 900);
DISPLAY 1.170213 (2225 900);
PAINT GREEN (2225 900);
DISPLAY INVISIBLE (2225 900);
FORCEPROP 1 LAST BODY_TYPE PLUMBING
J 0
(2105 907);
DISPLAY 0.340426 (2105 907);
PAINT GREEN (2105 907);
DISPLAY INVISIBLE (2105 907);
FORCEPROP 1 LAST PATH I105
J 0
(2225 950);
DISPLAY 0.872340 (2225 950);
PAINT AQUA (2225 950);
DISPLAY INVISIBLE (2225 950);
FORCEPROP 2 LAST ROOM PROCHOT_MEMHOT_ISO
J 0
(1775 1025);
PAINT ORANGE (1775 1025);
DISPLAY INVISIBLE (1775 1025);
FORCEPROP 1 LAST HDL_POWER GND
J 0
(2150 1100);
DISPLAY 1.170213 (2150 1100);
PAINT GREEN (2150 1100);
DISPLAY INVISIBLE (2150 1100);
FORCEADD RES..2
(2150 1800);
FORCEPROP 1 LAST LOCATION R7E7
J 0
(2195 1925);
DISPLAY 0.617021 (2195 1925);
PAINT AQUA (2195 1925);
FORCEPROP 1 LAST PART_NUMBER G21796-072
J 0
(2190 1675);
DISPLAY 0.617021 (2190 1675);
PAINT BLUE (2190 1675);
FORCEPROP 1 LAST VALUE 4.75K
J 0
(2195 1875);
DISPLAY 0.617021 (2195 1875);
PAINT SKYBLUE (2195 1875);
FORCEPROP 1 LAST TOLERANCE 1%
J 0
(2195 1825);
DISPLAY 0.617021 (2195 1825);
PAINT SKYBLUE (2195 1825);
FORCEPROP 1 LAST PACK_TYPE 0402
J 0
(2190 1625);
DISPLAY 0.617021 (2190 1625);
PAINT SKYBLUE (2190 1625);
FORCEPROP 1 LAST MATERIAL CHIP
J 0
(2190 1725);
DISPLAY 0.617021 (2190 1725);
PAINT SKYBLUE (2190 1725);
FORCEPROP 1 LAST WATTAGE 1/16W
J 0
(2190 1775);
DISPLAY 0.617021 (2190 1775);
PAINT SKYBLUE (2190 1775);
FORCEPROP 1 LASTPIN (2150 1700) $PN 2
J 0
(2155 1710);
DISPLAY 0.617021 (2155 1710);
PAINT ORANGE (2155 1710);
FORCEPROP 1 LASTPIN (2150 1900) $PN 1
J 0
(2155 1862);
DISPLAY 0.617021 (2155 1862);
PAINT ORANGE (2155 1862);
FORCEPROP 2 LAST CDS_LIB mstr_discrete
J 0
(2150 1800);
PAINT MONO (2150 1800);
DISPLAY INVISIBLE (2150 1800);
FORCEPROP 2 LAST SEC_TYPE 0402
J 0
(2200 2025);
DISPLAY 1.021277 (2200 2025);
PAINT ORANGE (2200 2025);
DISPLAY INVISIBLE (2200 2025);
FORCEPROP 2 LAST SEC 1
J 0
(2200 2025);
DISPLAY 0.680851 (2200 2025);
PAINT MONO (2200 2025);
DISPLAY INVISIBLE (2200 2025);
FORCEPROP 2 LAST CDS_LOCATION R7E7
J 0
(2195 1925);
DISPLAY 0.617021 (2195 1925);
PAINT AQUA (2195 1925);
DISPLAY INVISIBLE (2195 1925);
FORCEPROP 1 LAST PATH I106
J 0
(2200 1975);
DISPLAY 0.978723 (2200 1975);
PAINT WHITE (2200 1975);
DISPLAY INVISIBLE (2200 1975);
FORCEPROP 0 LAST ROOM PROC_SIDEBAND
J 0
(2200 2025);
DISPLAY 1.021277 (2200 2025);
PAINT ORANGE (2200 2025);
DISPLAY INVISIBLE (2200 2025);
FORCEADD P3V3..1
(2150 2075);
FORCEPROP 3 LASTPIN (2150 2025) SIG_NAME P3V3\g
J 0
(2160 2035);
DISPLAY 0.659574 (2160 2035);
PAINT MONO (2160 2035);
DISPLAY INVISIBLE (2160 2035);
FORCEPROP 1 LAST VOLTAGE 3.3V
J 0
(2105 2032);
DISPLAY 0.340426 (2105 2032);
PAINT SKYBLUE (2105 2032);
DISPLAY INVISIBLE (2105 2032);
FORCEPROP 2 LAST CDS_LIB mstr_symbols
J 0
(2150 2075);
PAINT MONO (2150 2075);
DISPLAY INVISIBLE (2150 2075);
FORCEPROP 1 LAST SIZE 1B
J 0
(2195 2097);
DISPLAY 0.446809 (2195 2097);
PAINT GREEN (2195 2097);
DISPLAY INVISIBLE (2195 2097);
FORCEPROP 1 LAST BODY_TYPE PLUMBING
J 0
(2105 2032);
DISPLAY 0.446809 (2105 2032);
PAINT GREEN (2105 2032);
DISPLAY INVISIBLE (2105 2032);
FORCEPROP 1 LAST PATH I107
J 0
(2195 2077);
DISPLAY 0.340426 (2195 2077);
PAINT GREEN (2195 2077);
DISPLAY INVISIBLE (2195 2077);
FORCEPROP 2 LAST ROOM PROCHOT_MEMHOT_ISO
J 0
(1950 2175);
DISPLAY 1.340426 (1950 2175);
PAINT ORANGE (1950 2175);
DISPLAY INVISIBLE (1950 2175);
FORCEPROP 1 LAST HDL_POWER P3V3
J 0
(1825 1950);
DISPLAY 1.170213 (1825 1950);
PAINT GREEN (1825 1950);
DISPLAY INVISIBLE (1825 1950);
FORCEADD RES..1
(1325 1250);
FORCEPROP 1 LAST LOCATION R7E9
J 0
(1275 1300);
DISPLAY 0.617021 (1275 1300);
PAINT AQUA (1275 1300);
FORCEPROP 1 LAST PART_NUMBER G21497-005
J 0
(1200 1100);
DISPLAY 0.617021 (1200 1100);
PAINT BLUE (1200 1100);
FORCEPROP 1 LAST VALUE 0.0
J 2
(1225 1200);
DISPLAY 0.617021 (1225 1200);
PAINT SKYBLUE (1225 1200);
FORCEPROP 1 LAST TOLERANCE 5%
J 0
(1425 1150);
DISPLAY 0.617021 (1425 1150);
PAINT SKYBLUE (1425 1150);
FORCEPROP 1 LAST PACK_TYPE 0402
J 0
(1200 1150);
DISPLAY 0.617021 (1200 1150);
PAINT SKYBLUE (1200 1150);
FORCEPROP 1 LAST MATERIAL CHIP
J 0
(1050 1150);
DISPLAY 0.617021 (1050 1150);
PAINT SKYBLUE (1050 1150);
FORCEPROP 1 LAST WATTAGE 1/16W
J 2
(1475 1200);
DISPLAY 0.617021 (1475 1200);
PAINT SKYBLUE (1475 1200);
FORCEPROP 1 LASTPIN (1425 1250) $PN 2
J 0
(1387 1262);
DISPLAY 0.617021 (1387 1262);
PAINT ORANGE (1387 1262);
FORCEPROP 1 LASTPIN (1225 1250) $PN 1
J 0
(1237 1262);
DISPLAY 0.617021 (1237 1262);
PAINT ORANGE (1237 1262);
FORCEPROP 2 LAST SEC_TYPE 0402
J 0
(1275 1450);
DISPLAY 1.021277 (1275 1450);
PAINT ORANGE (1275 1450);
DISPLAY INVISIBLE (1275 1450);
FORCEPROP 2 LAST CDS_LIB mstr_discrete
J 0
(1325 1250);
PAINT MONO (1325 1250);
DISPLAY INVISIBLE (1325 1250);
FORCEPROP 2 LAST BOM_COST PROC_SIDEBAND
J 2
(1325 1250);
PAINT MONO (1325 1250);
DISPLAY INVISIBLE (1325 1250);
FORCEPROP 2 LAST SEC 1
J 0
(1275 1450);
DISPLAY 0.680851 (1275 1450);
PAINT MONO (1275 1450);
DISPLAY INVISIBLE (1275 1450);
FORCEPROP 2 LAST CDS_LOCATION R7E9
J 0
(1275 1300);
DISPLAY 0.617021 (1275 1300);
PAINT AQUA (1275 1300);
DISPLAY INVISIBLE (1275 1300);
FORCEPROP 1 LAST PATH I108
J 0
(1275 1400);
DISPLAY 0.978723 (1275 1400);
PAINT WHITE (1275 1400);
DISPLAY INVISIBLE (1275 1400);
FORCEPROP 2 LAST ROOM PROC_SIDEBAND
J 0
(1250 1175);
DISPLAY 0.617021 (1250 1175);
PAINT ORANGE (1250 1175);
DISPLAY INVISIBLE (1250 1175);
FORCEADD OFFPAGE..1
(700 1250);
FORCEPROP 2 LAST $XR0 119 
J 0
(448 1250);
DISPLAY 0.638298 (448 1250);
PAINT MONO (448 1250);
FORCEPROP 2 LAST $XR1 133 
J 0
(328 1250);
DISPLAY 0.638298 (328 1250);
PAINT MONO (328 1250);
FORCEPROP 2 LAST $XR2 170 
J 0
(208 1250);
DISPLAY 0.638298 (208 1250);
PAINT MONO (208 1250);
FORCEPROP 2 LAST $XR3 120 
J 0
(88 1250);
DISPLAY 0.638298 (88 1250);
PAINT MONO (88 1250);
FORCEPROP 2 LAST $XR4 146 
J 0
(448 1214);
DISPLAY 0.638298 (448 1214);
PAINT MONO (448 1214);
FORCEPROP 2 LAST $XR5 ?
J 0
(448 1214);
DISPLAY 0.638298 (448 1214);
PAINT MONO (448 1214);
FORCEPROP 2 LAST CDS_LIB mstr_standard
J 0
(700 1250);
PAINT MONO (700 1250);
DISPLAY INVISIBLE (700 1250);
FORCEPROP 2 LAST ROOM PROCHOT_MEMHOT_ISO
J 0
(450 1300);
DISPLAY 0.978723 (450 1300);
PAINT ORANGE (450 1300);
DISPLAY INVISIBLE (450 1300);
FORCEPROP 1 LAST OFFPAGE TRUE
J 0
(1025 1125);
DISPLAY 0.978723 (1025 1125);
PAINT GREEN (1025 1125);
DISPLAY INVISIBLE (1025 1125);
FORCEPROP 1 LAST COMMENT_BODY TRUE
J 0
(825 1150);
DISPLAY 0.978723 (825 1150);
PAINT PEACH (825 1150);
DISPLAY INVISIBLE (825 1150);
FORCEPROP 2 LAST PATH I109
J 0
(750 1325);
DISPLAY 1.021277 (750 1325);
PAINT ORANGE (750 1325);
DISPLAY INVISIBLE (750 1325);
FORCEADD OFFPAGE..5
R 2
(3255 1600);
FORCEPROP 2 LAST $XR0 95 
J 0
(3444 1600);
DISPLAY 0.638298 (3444 1600);
PAINT MONO (3444 1600);
FORCEPROP 2 LAST CDS_LIB mstr_standard
J 0
(3255 1600);
PAINT MONO (3255 1600);
DISPLAY INVISIBLE (3255 1600);
FORCEPROP 1 LAST OFFPAGE TRUE
J 2
(2930 1475);
DISPLAY 0.978723 (2930 1475);
PAINT GREEN (2930 1475);
DISPLAY INVISIBLE (2930 1475);
FORCEPROP 1 LAST COMMENT_BODY TRUE
J 2
(3155 1525);
DISPLAY 0.978723 (3155 1525);
PAINT GREEN (3155 1525);
DISPLAY INVISIBLE (3155 1525);
FORCEPROP 2 LAST PATH I110
J 0
(3425 1675);
DISPLAY 1.021277 (3425 1675);
PAINT ORANGE (3425 1675);
DISPLAY INVISIBLE (3425 1675);
FORCEADD FET_N_DUAL..5
(2475 4325);
FORCEPROP 1 LAST LOCATION Q7E5
J 0
(2675 4325);
DISPLAY 0.617021 (2675 4325);
PAINT AQUA (2675 4325);
FORCEPROP 1 LAST PART_NUMBER E40049-001
J 0
(2675 4125);
DISPLAY 0.617021 (2675 4125);
PAINT BLUE (2675 4125);
FORCEPROP 1 LAST VALUE NTJD4001N
J 0
(2675 4275);
DISPLAY 0.617021 (2675 4275);
PAINT SKYBLUE (2675 4275);
FORCEPROP 1 LAST MATERIAL FET
J 0
(2675 4225);
DISPLAY 0.617021 (2675 4225);
PAINT SKYBLUE (2675 4225);
FORCEPROP 1 LASTPIN (2475 4125) $PN 1
J 2
(2533 4125);
DISPLAY 0.617021 (2533 4125);
PAINT WHITE (2533 4125);
FORCEPROP 1 LASTPIN (2275 4225) $PN 2
J 2
(2278 4240);
DISPLAY 0.617021 (2278 4240);
PAINT WHITE (2278 4240);
FORCEPROP 1 LASTPIN (2475 4525) $PN 6
J 2
(2528 4490);
DISPLAY 0.617021 (2528 4490);
PAINT WHITE (2528 4490);
FORCEPROP 1 LAST PACK_TYPE SMLF
J 0
(2675 4175);
DISPLAY 0.978723 (2675 4175);
PAINT SKYBLUE (2675 4175);
DISPLAY INVISIBLE (2675 4175);
FORCEPROP 2 LAST SEC_TYPE SMLF
J 0
(2675 4425);
DISPLAY 1.021277 (2675 4425);
PAINT ORANGE (2675 4425);
DISPLAY INVISIBLE (2675 4425);
FORCEPROP 2 LAST CDS_LIB mstr_discrete
J 0
(2475 4325);
PAINT MONO (2475 4325);
DISPLAY INVISIBLE (2475 4325);
FORCEPROP 2 LAST BOM_COST PROC_SIDEBAND
J 0
(2475 4325);
PAINT MONO (2475 4325);
DISPLAY INVISIBLE (2475 4325);
FORCEPROP 2 LAST SEC 1
J 0
(2675 4425);
DISPLAY 0.680851 (2675 4425);
PAINT MONO (2675 4425);
DISPLAY INVISIBLE (2675 4425);
FORCEPROP 2 LAST CDS_LOCATION Q7E5
J 0
(2675 4325);
DISPLAY 0.617021 (2675 4325);
PAINT AQUA (2675 4325);
DISPLAY INVISIBLE (2675 4325);
FORCEPROP 1 LAST PATH I111
J 0
(2675 4375);
DISPLAY 0.978723 (2675 4375);
PAINT BLUE (2675 4375);
DISPLAY INVISIBLE (2675 4375);
FORCEPROP 2 LAST ROOM HOT_EVENTS
J 0
(2675 4425);
PAINT ORANGE (2675 4425);
DISPLAY INVISIBLE (2675 4425);
FORCEADD FET_N_DUAL..5
(2550 2875);
FORCEPROP 1 LAST LOCATION Q7E6
J 0
(2750 2875);
DISPLAY 0.617021 (2750 2875);
PAINT AQUA (2750 2875);
FORCEPROP 1 LAST PART_NUMBER E40049-001
J 0
(2750 2675);
DISPLAY 0.617021 (2750 2675);
PAINT BLUE (2750 2675);
FORCEPROP 1 LAST VALUE NTJD4001N
J 0
(2750 2825);
DISPLAY 0.617021 (2750 2825);
PAINT SKYBLUE (2750 2825);
FORCEPROP 1 LAST MATERIAL FET
J 0
(2750 2775);
DISPLAY 0.617021 (2750 2775);
PAINT SKYBLUE (2750 2775);
FORCEPROP 1 LASTPIN (2550 2675) $PN 1
J 2
(2608 2675);
DISPLAY 0.617021 (2608 2675);
PAINT WHITE (2608 2675);
FORCEPROP 1 LASTPIN (2350 2775) $PN 2
J 2
(2353 2790);
DISPLAY 0.617021 (2353 2790);
PAINT WHITE (2353 2790);
FORCEPROP 1 LASTPIN (2550 3075) $PN 6
J 2
(2603 3040);
DISPLAY 0.617021 (2603 3040);
PAINT WHITE (2603 3040);
FORCEPROP 1 LAST PACK_TYPE SMLF
J 0
(2750 2725);
DISPLAY 0.978723 (2750 2725);
PAINT SKYBLUE (2750 2725);
DISPLAY INVISIBLE (2750 2725);
FORCEPROP 2 LAST SEC_TYPE SMLF
J 0
(2750 2975);
DISPLAY 1.021277 (2750 2975);
PAINT ORANGE (2750 2975);
DISPLAY INVISIBLE (2750 2975);
FORCEPROP 2 LAST BOM_COST PROC_SIDEBAND
J 0
(2550 2875);
PAINT MONO (2550 2875);
DISPLAY INVISIBLE (2550 2875);
FORCEPROP 2 LAST CDS_LIB mstr_discrete
J 0
(2550 2875);
PAINT MONO (2550 2875);
DISPLAY INVISIBLE (2550 2875);
FORCEPROP 2 LAST SEC 1
J 0
(2750 2975);
DISPLAY 0.680851 (2750 2975);
PAINT MONO (2750 2975);
DISPLAY INVISIBLE (2750 2975);
FORCEPROP 2 LAST CDS_LOCATION Q7E6
J 0
(2750 2875);
DISPLAY 0.617021 (2750 2875);
PAINT AQUA (2750 2875);
DISPLAY INVISIBLE (2750 2875);
FORCEPROP 1 LAST PATH I112
J 0
(2750 2925);
DISPLAY 0.978723 (2750 2925);
PAINT BLUE (2750 2925);
DISPLAY INVISIBLE (2750 2925);
FORCEPROP 2 LAST ROOM HOT_EVENTS
J 0
(2750 2975);
PAINT ORANGE (2750 2975);
DISPLAY INVISIBLE (2750 2975);
FORCEADD FET_N_DUAL..5
(-3100 1950);
FORCEPROP 1 LAST LOCATION Q2U1
J 0
(-2900 2100);
DISPLAY 0.617021 (-2900 2100);
PAINT AQUA (-2900 2100);
FORCEPROP 1 LAST PART_NUMBER E40049-001
J 0
(-2900 1950);
DISPLAY 0.617021 (-2900 1950);
PAINT BLUE (-2900 1950);
FORCEPROP 1 LAST VALUE NTJD4001N
J 0
(-2900 2050);
DISPLAY 0.617021 (-2900 2050);
PAINT SKYBLUE (-2900 2050);
FORCEPROP 1 LAST MATERIAL FET
J 0
(-2900 2000);
DISPLAY 0.617021 (-2900 2000);
PAINT SKYBLUE (-2900 2000);
FORCEPROP 1 LASTPIN (-3100 1750) $PN 4
J 2
(-3042 1750);
DISPLAY 0.617021 (-3042 1750);
PAINT WHITE (-3042 1750);
FORCEPROP 1 LASTPIN (-3300 1850) $PN 5
J 2
(-3297 1865);
DISPLAY 0.617021 (-3297 1865);
PAINT WHITE (-3297 1865);
FORCEPROP 1 LASTPIN (-3100 2150) $PN 3
J 2
(-3047 2115);
DISPLAY 0.617021 (-3047 2115);
PAINT WHITE (-3047 2115);
FORCEPROP 1 LAST PACK_TYPE SMLF
J 0
(-2900 1800);
PAINT SKYBLUE (-2900 1800);
DISPLAY INVISIBLE (-2900 1800);
FORCEPROP 2 LAST SEC_TYPE SMLF
J 0
(-2900 2150);
DISPLAY 1.021277 (-2900 2150);
PAINT ORANGE (-2900 2150);
DISPLAY INVISIBLE (-2900 2150);
FORCEPROP 2 LAST CDS_LIB mstr_discrete
J 0
(-3100 1950);
PAINT ORANGE (-3100 1950);
DISPLAY INVISIBLE (-3100 1950);
FORCEPROP 2 LAST BOM_COST PROC_SIDEBAND
J 0
(-3100 1950);
PAINT MONO (-3100 1950);
DISPLAY INVISIBLE (-3100 1950);
FORCEPROP 2 LAST SEC 2
J 0
(-2900 2150);
DISPLAY 0.680851 (-2900 2150);
PAINT MONO (-2900 2150);
DISPLAY INVISIBLE (-2900 2150);
FORCEPROP 2 LAST CDS_LOCATION Q2U1
J 0
(-2900 2100);
DISPLAY 0.617021 (-2900 2100);
PAINT AQUA (-2900 2100);
DISPLAY INVISIBLE (-2900 2100);
FORCEPROP 1 LAST PATH I113
J 0
(-2900 2000);
DISPLAY 0.978723 (-2900 2000);
PAINT BLUE (-2900 2000);
DISPLAY INVISIBLE (-2900 2000);
FORCEPROP 2 LAST ROOM PROC_SIDEBAND
J 1
(-2900 2200);
PAINT ORANGE (-2900 2200);
DISPLAY INVISIBLE (-2900 2200);
FORCEADD P3V3_STBY..1
(1125 3675);
FORCEPROP 3 LASTPIN (1125 3625) SIG_NAME P3V3_STBY\g
J 0
(1135 3635);
DISPLAY 0.659574 (1135 3635);
PAINT MONO (1135 3635);
DISPLAY INVISIBLE (1135 3635);
FORCEPROP 1 LAST VOLTAGE 3.3V
J 0
(1080 3632);
DISPLAY 0.340426 (1080 3632);
PAINT SKYBLUE (1080 3632);
DISPLAY INVISIBLE (1080 3632);
FORCEPROP 1 LAST SIZE 1B
J 0
(1170 3697);
DISPLAY 0.340426 (1170 3697);
PAINT GREEN (1170 3697);
DISPLAY INVISIBLE (1170 3697);
FORCEPROP 2 LAST CDS_LIB mstr_symbols
J 0
(1125 3675);
PAINT ORANGE (1125 3675);
DISPLAY INVISIBLE (1125 3675);
FORCEPROP 1 LAST BODY_TYPE PLUMBING
J 0
(1080 3632);
DISPLAY 0.340426 (1080 3632);
PAINT GREEN (1080 3632);
DISPLAY INVISIBLE (1080 3632);
FORCEPROP 1 LAST PATH I114
J 0
(1170 3677);
DISPLAY 0.340426 (1170 3677);
PAINT GREEN (1170 3677);
DISPLAY INVISIBLE (1170 3677);
FORCEPROP 1 LAST HDL_POWER P3V3_STBY
J 0
(825 3550);
DISPLAY 0.872340 (825 3550);
PAINT ORANGE (825 3550);
DISPLAY INVISIBLE (825 3550);
FORCEADD CAP_A..1
(1125 3450);
FORCEPROP 1 LAST LOCATION C7E4
J 0
(1175 3550);
DISPLAY 0.617021 (1175 3550);
PAINT AQUA (1175 3550);
FORCEPROP 1 LAST PART_NUMBER A36096-030
J 0
(1175 3300);
DISPLAY 0.617021 (1175 3300);
PAINT BLUE (1175 3300);
FORCEPROP 1 LAST VALUE 0.1UF
J 0
(1175 3500);
DISPLAY 0.617021 (1175 3500);
PAINT SKYBLUE (1175 3500);
FORCEPROP 1 LAST TOLERANCE 10%
J 0
(1175 3400);
DISPLAY 0.617021 (1175 3400);
PAINT SKYBLUE (1175 3400);
FORCEPROP 1 LAST PACK_TYPE 0402V
J 0
(1175 3250);
DISPLAY 0.617021 (1175 3250);
PAINT SKYBLUE (1175 3250);
FORCEPROP 1 LAST VOLTAGE 16V
J 0
(1175 3450);
DISPLAY 0.617021 (1175 3450);
PAINT SKYBLUE (1175 3450);
FORCEPROP 1 LAST MATERIAL X7R
J 0
(1175 3350);
DISPLAY 0.617021 (1175 3350);
PAINT SKYBLUE (1175 3350);
FORCEPROP 1 LASTPIN (1125 3550) $PN 1
J 0
(1135 3530);
DISPLAY 0.617021 (1135 3530);
PAINT ORANGE (1135 3530);
FORCEPROP 1 LASTPIN (1125 3350) $PN 2
J 0
(1135 3330);
DISPLAY 0.617021 (1135 3330);
PAINT ORANGE (1135 3330);
FORCEPROP 1 LAST PATH I115
J 0
(1175 3600);
DISPLAY 0.978723 (1175 3600);
PAINT WHITE (1175 3600);
DISPLAY INVISIBLE (1175 3600);
FORCEPROP 2 LAST ROOM PROC_SIDEBAND
J 0
(1175 3600);
DISPLAY 1.021277 (1175 3600);
PAINT ORANGE (1175 3600);
DISPLAY INVISIBLE (1175 3600);
FORCEPROP 2 LAST CDS_LOCATION C7E4
J 0
(1175 3550);
DISPLAY 0.617021 (1175 3550);
PAINT AQUA (1175 3550);
DISPLAY INVISIBLE (1175 3550);
FORCEPROP 2 LAST BOM_COST PROC_SIDEBAND
J 0
(1175 3650);
DISPLAY 1.021277 (1175 3650);
PAINT ORANGE (1175 3650);
DISPLAY INVISIBLE (1175 3650);
FORCEPROP 2 LAST CDS_LIB dev_discrete
J 0
(1125 3450);
PAINT ORANGE (1125 3450);
DISPLAY INVISIBLE (1125 3450);
FORCEPROP 2 LAST CDS_SEC 1
J 0
(1175 3600);
PAINT ORANGE (1175 3600);
DISPLAY INVISIBLE (1175 3600);
FORCEPROP 2 LAST SEC_TYPE 0402V
J 0
(1175 3650);
DISPLAY 1.021277 (1175 3650);
PAINT ORANGE (1175 3650);
DISPLAY INVISIBLE (1175 3650);
FORCEPROP 2 LAST SEC 1
J 0
(1175 3650);
DISPLAY 0.680851 (1175 3650);
PAINT MONO (1175 3650);
DISPLAY INVISIBLE (1175 3650);
FORCEADD GND..1
(1125 3200);
FORCEPROP 3 LASTPIN (1125 3250) SIG_NAME GND\g
J 0
(1135 3260);
DISPLAY 0.659574 (1135 3260);
PAINT MONO (1135 3260);
DISPLAY INVISIBLE (1135 3260);
FORCEPROP 1 LAST VOLTAGE 0.0V
J 0
(1080 3157);
DISPLAY 0.340426 (1080 3157);
PAINT SKYBLUE (1080 3157);
DISPLAY INVISIBLE (1080 3157);
FORCEPROP 1 LAST SIZE 1B
J 0
(1200 3150);
DISPLAY 0.872340 (1200 3150);
PAINT AQUA (1200 3150);
DISPLAY INVISIBLE (1200 3150);
FORCEPROP 2 LAST CDS_LIB mstr_symbols
J 0
(1125 3200);
PAINT ORANGE (1125 3200);
DISPLAY INVISIBLE (1125 3200);
FORCEPROP 1 LAST BODY_TYPE PLUMBING
J 0
(1080 3157);
DISPLAY 0.340426 (1080 3157);
PAINT GREEN (1080 3157);
DISPLAY INVISIBLE (1080 3157);
FORCEPROP 1 LAST PATH I116
J 0
(1200 3200);
DISPLAY 0.872340 (1200 3200);
PAINT AQUA (1200 3200);
DISPLAY INVISIBLE (1200 3200);
FORCEPROP 1 LAST HDL_POWER GND
J 0
(1125 3350);
DISPLAY 0.872340 (1125 3350);
PAINT GREEN (1125 3350);
DISPLAY INVISIBLE (1125 3350);
FORCEADD TTL1G08..1
(1550 4225);
FORCEPROP 1 LAST POWER_GROUP VCC=P3V3_STBY;GND=GND;
J 1
(1575 4050);
DISPLAY 0.617021 (1575 4050);
PAINT ORANGE (1575 4050);
FORCEPROP 1 LAST LOCATION U7E2
J 1
(1525 4360);
DISPLAY 0.617021 (1525 4360);
PAINT AQUA (1525 4360);
FORCEPROP 1 LAST PART_NUMBER D10321-001
J 1
(1525 4325);
DISPLAY 0.617021 (1525 4325);
PAINT BLUE (1525 4325);
FORCEPROP 1 LAST VALUE NC7SZ08
J 1
(1550 4100);
DISPLAY 0.617021 (1550 4100);
PAINT SKYBLUE (1550 4100);
FORCEPROP 1 LAST PACK_TYPE SOTLF
J 1
(1525 4400);
DISPLAY 0.617021 (1525 4400);
PAINT SKYBLUE (1525 4400);
FORCEPROP 1 LAST MATERIAL IC
J 1
(1525 4435);
DISPLAY 0.617021 (1525 4435);
PAINT SKYBLUE (1525 4435);
FORCEPROP 2 LASTPIN (1700 4225) $PN 4
J 0
(1710 4235);
DISPLAY 0.617021 (1710 4235);
PAINT ORANGE (1710 4235);
FORCEPROP 2 LASTPIN (1400 4175) $PN 2
J 2
(1390 4185);
DISPLAY 0.617021 (1390 4185);
PAINT ORANGE (1390 4185);
FORCEPROP 2 LASTPIN (1400 4275) $PN 1
J 2
(1390 4285);
DISPLAY 0.617021 (1390 4285);
PAINT ORANGE (1390 4285);
FORCEPROP 2 LAST SEC_TYPE SOTLF
J 0
(1550 4525);
DISPLAY 1.021277 (1550 4525);
PAINT ORANGE (1550 4525);
DISPLAY INVISIBLE (1550 4525);
FORCEPROP 0 LAST BOM_COST PROC_SIDEBAND
J 0
(1525 4625);
DISPLAY 1.021277 (1525 4625);
PAINT ORANGE (1525 4625);
DISPLAY INVISIBLE (1525 4625);
FORCEPROP 2 LAST CDS_LIB mstr_ttl
J 0
(1550 4225);
PAINT ORANGE (1550 4225);
DISPLAY INVISIBLE (1550 4225);
FORCEPROP 2 LAST SEC 1
J 0
(1550 4525);
DISPLAY 0.680851 (1550 4525);
PAINT MONO (1550 4525);
DISPLAY INVISIBLE (1550 4525);
FORCEPROP 2 LAST CDS_LOCATION U7E2
J 1
(1525 4360);
DISPLAY 0.617021 (1525 4360);
PAINT AQUA (1525 4360);
DISPLAY INVISIBLE (1525 4360);
FORCEPROP 1 LAST PATH I117
J 1
(1530 4490);
DISPLAY 0.702128 (1530 4490);
PAINT WHITE (1530 4490);
DISPLAY INVISIBLE (1530 4490);
FORCEPROP 0 LAST ROOM CAT_ERR
J 0
(1525 4525);
DISPLAY 1.021277 (1525 4525);
PAINT ORANGE (1525 4525);
DISPLAY INVISIBLE (1525 4525);
FORCEADD TTL1G08..1
(1575 2775);
FORCEPROP 1 LAST POWER_GROUP VCC=P3V3_STBY;GND=GND;
J 1
(1600 2600);
DISPLAY 0.617021 (1600 2600);
PAINT ORANGE (1600 2600);
FORCEPROP 1 LAST LOCATION U7E3
J 1
(1550 2910);
DISPLAY 0.617021 (1550 2910);
PAINT AQUA (1550 2910);
FORCEPROP 1 LAST PART_NUMBER D10321-001
J 1
(1550 2875);
DISPLAY 0.617021 (1550 2875);
PAINT BLUE (1550 2875);
FORCEPROP 1 LAST VALUE NC7SZ08
J 1
(1575 2650);
DISPLAY 0.617021 (1575 2650);
PAINT SKYBLUE (1575 2650);
FORCEPROP 1 LAST PACK_TYPE SOTLF
J 1
(1550 2950);
DISPLAY 0.617021 (1550 2950);
PAINT SKYBLUE (1550 2950);
FORCEPROP 1 LAST MATERIAL IC
J 1
(1550 2985);
DISPLAY 0.617021 (1550 2985);
PAINT SKYBLUE (1550 2985);
FORCEPROP 2 LASTPIN (1725 2775) $PN 4
J 0
(1735 2785);
DISPLAY 0.617021 (1735 2785);
PAINT ORANGE (1735 2785);
FORCEPROP 2 LASTPIN (1425 2725) $PN 2
J 2
(1415 2735);
DISPLAY 0.617021 (1415 2735);
PAINT ORANGE (1415 2735);
FORCEPROP 2 LASTPIN (1425 2825) $PN 1
J 2
(1415 2835);
DISPLAY 0.617021 (1415 2835);
PAINT ORANGE (1415 2835);
FORCEPROP 0 LAST BOM_COST PROC_SIDEBAND
J 0
(1550 3175);
DISPLAY 1.021277 (1550 3175);
PAINT ORANGE (1550 3175);
DISPLAY INVISIBLE (1550 3175);
FORCEPROP 2 LAST CDS_LIB mstr_ttl
J 0
(1575 2775);
PAINT ORANGE (1575 2775);
DISPLAY INVISIBLE (1575 2775);
FORCEPROP 2 LAST SEC_TYPE SOTLF
J 0
(1575 3075);
DISPLAY 1.021277 (1575 3075);
PAINT ORANGE (1575 3075);
DISPLAY INVISIBLE (1575 3075);
FORCEPROP 2 LAST SEC 1
J 0
(1575 3075);
DISPLAY 0.680851 (1575 3075);
PAINT MONO (1575 3075);
DISPLAY INVISIBLE (1575 3075);
FORCEPROP 2 LAST CDS_LOCATION U7E3
J 1
(1550 2910);
DISPLAY 0.617021 (1550 2910);
PAINT AQUA (1550 2910);
DISPLAY INVISIBLE (1550 2910);
FORCEPROP 1 LAST PATH I118
J 1
(1555 3040);
DISPLAY 0.702128 (1555 3040);
PAINT WHITE (1555 3040);
DISPLAY INVISIBLE (1555 3040);
FORCEPROP 0 LAST ROOM CAT_ERR
J 0
(1550 3075);
DISPLAY 1.021277 (1550 3075);
PAINT ORANGE (1550 3075);
DISPLAY INVISIBLE (1550 3075);
FORCEADD FET_N..8
(-3100 4550);
FORCEPROP 1 LAST LOCATION Q7E8
J 0
(-2900 4550);
DISPLAY 0.617021 (-2900 4550);
PAINT AQUA (-2900 4550);
FORCEPROP 1 LAST VALUE 2N7002
J 0
(-2900 4500);
DISPLAY 0.617021 (-2900 4500);
PAINT SKYBLUE (-2900 4500);
FORCEPROP 1 LAST MATERIAL FET
J 0
(-2900 4450);
DISPLAY 0.617021 (-2900 4450);
PAINT SKYBLUE (-2900 4450);
FORCEPROP 1 LASTPIN (-3100 4350) $PN 2
J 2
(-3042 4350);
DISPLAY 0.617021 (-3042 4350);
PAINT WHITE (-3042 4350);
FORCEPROP 1 LASTPIN (-3300 4450) $PN 1
J 2
(-3297 4465);
DISPLAY 0.617021 (-3297 4465);
PAINT WHITE (-3297 4465);
FORCEPROP 1 LASTPIN (-3100 4750) $PN 3
J 2
(-3047 4715);
DISPLAY 0.617021 (-3047 4715);
PAINT WHITE (-3047 4715);
FORCEPROP 1 LAST PART_NUMBER C79254-001
J 0
(-2900 4350);
DISPLAY 0.617021 (-2900 4350);
PAINT BLUE (-2900 4350);
FORCEPROP 1 LAST PACK_TYPE SOT23
J 0
(-2900 4400);
DISPLAY 0.978723 (-2900 4400);
PAINT SKYBLUE (-2900 4400);
DISPLAY INVISIBLE (-2900 4400);
FORCEPROP 2 LAST SEC_TYPE SOT23
J 0
(-2900 4650);
DISPLAY 1.021277 (-2900 4650);
PAINT ORANGE (-2900 4650);
DISPLAY INVISIBLE (-2900 4650);
FORCEPROP 2 LAST CDS_LIB mstr_discrete
J 0
(-3100 4550);
PAINT ORANGE (-3100 4550);
DISPLAY INVISIBLE (-3100 4550);
FORCEPROP 2 LAST SEC 1
J 0
(-2900 4650);
DISPLAY 0.680851 (-2900 4650);
PAINT MONO (-2900 4650);
DISPLAY INVISIBLE (-2900 4650);
FORCEPROP 1 LAST PATH I119
J 0
(-2900 4600);
DISPLAY 0.978723 (-2900 4600);
PAINT BLUE (-2900 4600);
DISPLAY INVISIBLE (-2900 4600);
FORCEPROP 0 LAST ROOM PROC_SIDEBAND
J 0
(-2900 4650);
DISPLAY 1.021277 (-2900 4650);
PAINT ORANGE (-2900 4650);
DISPLAY INVISIBLE (-2900 4650);
FORCEADD OFFPAGE..2
(-700 3525);
FORCEPROP 2 LAST $XR0 55 
J 0
(-511 3525);
DISPLAY 0.638298 (-511 3525);
PAINT MONO (-511 3525);
FORCEPROP 2 LAST $XR1 95 
J 0
(-421 3525);
DISPLAY 0.638298 (-421 3525);
PAINT MONO (-421 3525);
FORCEPROP 2 LAST $XR2 93 
J 0
(-331 3525);
DISPLAY 0.638298 (-331 3525);
PAINT MONO (-331 3525);
FORCEPROP 2 LAST CDS_LIB mstr_standard
J 0
(-700 3525);
PAINT ORANGE (-700 3525);
DISPLAY INVISIBLE (-700 3525);
FORCEPROP 2 LAST ROOM SMART_CLST
J 0
(-950 3600);
DISPLAY 1.361702 (-950 3600);
PAINT ORANGE (-950 3600);
DISPLAY INVISIBLE (-950 3600);
FORCEPROP 1 LAST OFFPAGE TRUE
J 0
(-375 3400);
PAINT GREEN (-375 3400);
DISPLAY INVISIBLE (-375 3400);
FORCEPROP 1 LAST COMMENT_BODY TRUE
J 0
(-745 3430);
DISPLAY 1.170213 (-745 3430);
PAINT GREEN (-745 3430);
DISPLAY INVISIBLE (-745 3430);
FORCEPROP 2 LAST PATH I12
J 0
(-225 3575);
DISPLAY 1.021277 (-225 3575);
PAINT ORANGE (-225 3575);
DISPLAY INVISIBLE (-225 3575);
FORCEADD GND..1
(-3100 4250);
FORCEPROP 3 LASTPIN (-3100 4300) SIG_NAME GND\g
J 0
(-3090 4310);
DISPLAY 0.659574 (-3090 4310);
PAINT MONO (-3090 4310);
DISPLAY INVISIBLE (-3090 4310);
FORCEPROP 1 LAST VOLTAGE 0
J 0
(-3100 4250);
PAINT SKYBLUE (-3100 4250);
DISPLAY INVISIBLE (-3100 4250);
FORCEPROP 2 LAST CDS_LIB mstr_symbols
J 0
(-3100 4250);
PAINT ORANGE (-3100 4250);
DISPLAY INVISIBLE (-3100 4250);
FORCEPROP 1 LAST SIZE 1B
J 0
(-3025 4200);
DISPLAY 1.170213 (-3025 4200);
PAINT GREEN (-3025 4200);
DISPLAY INVISIBLE (-3025 4200);
FORCEPROP 1 LAST BODY_TYPE PLUMBING
J 0
(-3145 4207);
DISPLAY 0.340426 (-3145 4207);
PAINT GREEN (-3145 4207);
DISPLAY INVISIBLE (-3145 4207);
FORCEPROP 1 LAST PATH I120
J 0
(-3025 4250);
DISPLAY 0.872340 (-3025 4250);
PAINT AQUA (-3025 4250);
DISPLAY INVISIBLE (-3025 4250);
FORCEPROP 1 LAST HDL_POWER GND
J 0
(-3100 4400);
DISPLAY 1.170213 (-3100 4400);
PAINT GREEN (-3100 4400);
DISPLAY INVISIBLE (-3100 4400);
FORCEADD OFFPAGE..2
(-700 4850);
FORCEPROP 2 LAST $XR0 108 
J 0
(-511 4850);
DISPLAY 0.638298 (-511 4850);
PAINT MONO (-511 4850);
FORCEPROP 2 LAST CDS_LIB mstr_standard
J 0
(-700 4850);
PAINT ORANGE (-700 4850);
DISPLAY INVISIBLE (-700 4850);
FORCEPROP 2 LAST ROOM SMART_CLST
J 0
(-950 4925);
DISPLAY 1.361702 (-950 4925);
PAINT ORANGE (-950 4925);
DISPLAY INVISIBLE (-950 4925);
FORCEPROP 1 LAST OFFPAGE TRUE
J 0
(-375 4725);
PAINT GREEN (-375 4725);
DISPLAY INVISIBLE (-375 4725);
FORCEPROP 1 LAST COMMENT_BODY TRUE
J 0
(-745 4755);
DISPLAY 1.170213 (-745 4755);
PAINT GREEN (-745 4755);
DISPLAY INVISIBLE (-745 4755);
FORCEPROP 2 LAST PATH I121
J 0
(-525 4925);
DISPLAY 1.021277 (-525 4925);
PAINT ORANGE (-525 4925);
DISPLAY INVISIBLE (-525 4925);
FORCEADD OFFPAGE..2
(-700 2850);
FORCEPROP 2 LAST $XR0 94 
J 0
(-511 2850);
DISPLAY 0.638298 (-511 2850);
PAINT MONO (-511 2850);
FORCEPROP 2 LAST $XR1 21 
J 0
(-421 2850);
DISPLAY 0.638298 (-421 2850);
PAINT MONO (-421 2850);
FORCEPROP 2 LAST $XR2 152 
J 0
(-331 2850);
DISPLAY 0.638298 (-331 2850);
PAINT MONO (-331 2850);
FORCEPROP 2 LAST ROOM SMART_CLST
J 0
(-950 2925);
DISPLAY 1.361702 (-950 2925);
PAINT ORANGE (-950 2925);
DISPLAY INVISIBLE (-950 2925);
FORCEPROP 2 LAST CDS_LIB mstr_standard
J 0
(-700 2850);
PAINT ORANGE (-700 2850);
DISPLAY INVISIBLE (-700 2850);
FORCEPROP 1 LAST OFFPAGE TRUE
J 0
(-375 2725);
PAINT GREEN (-375 2725);
DISPLAY INVISIBLE (-375 2725);
FORCEPROP 1 LAST COMMENT_BODY TRUE
J 0
(-745 2755);
DISPLAY 1.170213 (-745 2755);
PAINT GREEN (-745 2755);
DISPLAY INVISIBLE (-745 2755);
FORCEPROP 2 LAST PATH I13
J 0
(-400 2900);
DISPLAY 1.021277 (-400 2900);
PAINT ORANGE (-400 2900);
DISPLAY INVISIBLE (-400 2900);
FORCEADD OFFPAGE..2
(-675 2200);
FORCEPROP 2 LAST $XR0 94 
J 0
(-486 2200);
DISPLAY 0.638298 (-486 2200);
PAINT MONO (-486 2200);
FORCEPROP 2 LAST $XR1 21 
J 0
(-396 2200);
DISPLAY 0.638298 (-396 2200);
PAINT MONO (-396 2200);
FORCEPROP 2 LAST $XR2 152 
J 0
(-306 2200);
DISPLAY 0.638298 (-306 2200);
PAINT MONO (-306 2200);
FORCEPROP 2 LAST ROOM SMART_CLST
J 0
(-925 2275);
DISPLAY 1.361702 (-925 2275);
PAINT ORANGE (-925 2275);
DISPLAY INVISIBLE (-925 2275);
FORCEPROP 2 LAST CDS_LIB mstr_standard
J 0
(-675 2200);
PAINT ORANGE (-675 2200);
DISPLAY INVISIBLE (-675 2200);
FORCEPROP 1 LAST OFFPAGE TRUE
J 0
(-350 2075);
PAINT GREEN (-350 2075);
DISPLAY INVISIBLE (-350 2075);
FORCEPROP 1 LAST COMMENT_BODY TRUE
J 0
(-720 2105);
DISPLAY 1.170213 (-720 2105);
PAINT GREEN (-720 2105);
DISPLAY INVISIBLE (-720 2105);
FORCEPROP 2 LAST PATH I14
J 0
(-375 2250);
DISPLAY 1.021277 (-375 2250);
PAINT ORANGE (-375 2250);
DISPLAY INVISIBLE (-375 2250);
FORCEADD OFFPAGE..2
(-675 1550);
FORCEPROP 2 LAST $XR0 55 
J 0
(-486 1550);
DISPLAY 0.638298 (-486 1550);
PAINT MONO (-486 1550);
FORCEPROP 2 LAST $XR1 94 
J 0
(-396 1550);
DISPLAY 0.638298 (-396 1550);
PAINT MONO (-396 1550);
FORCEPROP 2 LAST $XR2 152 
J 0
(-306 1550);
DISPLAY 0.638298 (-306 1550);
PAINT MONO (-306 1550);
FORCEPROP 2 LAST ROOM PROC_SIDEBAND
J 0
(-925 1625);
DISPLAY 1.361702 (-925 1625);
PAINT ORANGE (-925 1625);
DISPLAY INVISIBLE (-925 1625);
FORCEPROP 2 LAST CDS_LIB mstr_standard
J 0
(-675 1550);
PAINT ORANGE (-675 1550);
DISPLAY INVISIBLE (-675 1550);
FORCEPROP 1 LAST OFFPAGE TRUE
J 0
(-350 1425);
PAINT GREEN (-350 1425);
DISPLAY INVISIBLE (-350 1425);
FORCEPROP 1 LAST COMMENT_BODY TRUE
J 0
(-720 1455);
DISPLAY 1.170213 (-720 1455);
PAINT GREEN (-720 1455);
DISPLAY INVISIBLE (-720 1455);
FORCEPROP 2 LAST PATH I18
J 0
(-375 1600);
DISPLAY 1.021277 (-375 1600);
PAINT ORANGE (-375 1600);
DISPLAY INVISIBLE (-375 1600);
FORCEADD OFFPAGE..2
(-675 925);
FORCEPROP 2 LAST $XR0 55 
J 0
(-486 925);
DISPLAY 0.638298 (-486 925);
PAINT MONO (-486 925);
FORCEPROP 2 LAST $XR1 94 
J 0
(-396 925);
DISPLAY 0.638298 (-396 925);
PAINT MONO (-396 925);
FORCEPROP 2 LAST $XR2 152 
J 0
(-306 925);
DISPLAY 0.638298 (-306 925);
PAINT MONO (-306 925);
FORCEPROP 2 LAST CDS_LIB mstr_standard
J 0
(-675 925);
PAINT ORANGE (-675 925);
DISPLAY INVISIBLE (-675 925);
FORCEPROP 2 LAST ROOM SMART_CLST
J 0
(-925 1000);
DISPLAY 1.361702 (-925 1000);
PAINT ORANGE (-925 1000);
DISPLAY INVISIBLE (-925 1000);
FORCEPROP 1 LAST OFFPAGE TRUE
J 0
(-350 800);
PAINT GREEN (-350 800);
DISPLAY INVISIBLE (-350 800);
FORCEPROP 1 LAST COMMENT_BODY TRUE
J 0
(-720 830);
DISPLAY 1.170213 (-720 830);
PAINT GREEN (-720 830);
DISPLAY INVISIBLE (-720 830);
FORCEPROP 2 LAST PATH I19
J 0
(-375 975);
DISPLAY 1.021277 (-375 975);
PAINT ORANGE (-375 975);
DISPLAY INVISIBLE (-375 975);
FORCEADD OFFPAGE..4
(-2475 5025);
FORCEPROP 2 LAST $XR0 95 
J 0
(-2289 5025);
DISPLAY 0.638298 (-2289 5025);
PAINT MONO (-2289 5025);
FORCEPROP 2 LAST CDS_LIB mstr_standard
J 0
(-2475 5025);
PAINT MONO (-2475 5025);
DISPLAY INVISIBLE (-2475 5025);
FORCEPROP 1 LAST OFFPAGE TRUE
J 0
(-2150 4900);
PAINT GREEN (-2150 4900);
DISPLAY INVISIBLE (-2150 4900);
FORCEPROP 1 LAST COMMENT_BODY TRUE
J 0
(-2500 4925);
DISPLAY 1.212766 (-2500 4925);
PAINT GREEN (-2500 4925);
DISPLAY INVISIBLE (-2500 4925);
FORCEPROP 2 LAST PATH I22
J 0
(-2275 5075);
DISPLAY 1.021277 (-2275 5075);
PAINT ORANGE (-2275 5075);
DISPLAY INVISIBLE (-2275 5075);
FORCEADD GND..1
(-3100 3675);
FORCEPROP 3 LASTPIN (-3100 3725) SIG_NAME GND\g
J 0
(-3090 3735);
DISPLAY 0.659574 (-3090 3735);
PAINT MONO (-3090 3735);
DISPLAY INVISIBLE (-3090 3735);
FORCEPROP 1 LAST VOLTAGE 0
J 0
(-3100 3675);
PAINT SKYBLUE (-3100 3675);
DISPLAY INVISIBLE (-3100 3675);
FORCEPROP 1 LAST SIZE 1B
J 0
(-3025 3625);
DISPLAY 1.170213 (-3025 3625);
PAINT GREEN (-3025 3625);
DISPLAY INVISIBLE (-3025 3625);
FORCEPROP 2 LAST CDS_LIB mstr_symbols
J 1
(-3100 3675);
PAINT ORANGE (-3100 3675);
DISPLAY INVISIBLE (-3100 3675);
FORCEPROP 1 LAST BODY_TYPE PLUMBING
J 0
(-3145 3632);
DISPLAY 0.340426 (-3145 3632);
PAINT GREEN (-3145 3632);
DISPLAY INVISIBLE (-3145 3632);
FORCEPROP 1 LAST PATH I23
J 0
(-3025 3675);
DISPLAY 0.872340 (-3025 3675);
PAINT AQUA (-3025 3675);
DISPLAY INVISIBLE (-3025 3675);
FORCEPROP 1 LAST HDL_POWER GND
J 0
(-3100 3825);
DISPLAY 1.170213 (-3100 3825);
PAINT GREEN (-3100 3825);
DISPLAY INVISIBLE (-3100 3825);
FORCEADD GND..1
(-3100 3000);
FORCEPROP 3 LASTPIN (-3100 3050) SIG_NAME GND\g
J 0
(-3090 3060);
DISPLAY 0.659574 (-3090 3060);
PAINT MONO (-3090 3060);
DISPLAY INVISIBLE (-3090 3060);
FORCEPROP 1 LAST VOLTAGE 0
J 0
(-3100 3000);
PAINT SKYBLUE (-3100 3000);
DISPLAY INVISIBLE (-3100 3000);
FORCEPROP 2 LAST CDS_LIB mstr_symbols
J 1
(-3100 3000);
PAINT ORANGE (-3100 3000);
DISPLAY INVISIBLE (-3100 3000);
FORCEPROP 1 LAST SIZE 1B
J 0
(-3025 2950);
DISPLAY 1.170213 (-3025 2950);
PAINT GREEN (-3025 2950);
DISPLAY INVISIBLE (-3025 2950);
FORCEPROP 1 LAST BODY_TYPE PLUMBING
J 0
(-3145 2957);
DISPLAY 0.340426 (-3145 2957);
PAINT GREEN (-3145 2957);
DISPLAY INVISIBLE (-3145 2957);
FORCEPROP 1 LAST PATH I26
J 0
(-3025 3000);
DISPLAY 0.872340 (-3025 3000);
PAINT AQUA (-3025 3000);
DISPLAY INVISIBLE (-3025 3000);
FORCEPROP 1 LAST HDL_POWER GND
J 0
(-3100 3150);
DISPLAY 1.170213 (-3100 3150);
PAINT GREEN (-3100 3150);
DISPLAY INVISIBLE (-3100 3150);
FORCEADD GND..1
(-3100 2350);
FORCEPROP 3 LASTPIN (-3100 2400) SIG_NAME GND\g
J 0
(-3090 2410);
DISPLAY 0.659574 (-3090 2410);
PAINT MONO (-3090 2410);
DISPLAY INVISIBLE (-3090 2410);
FORCEPROP 1 LAST VOLTAGE 0
J 0
(-3100 2350);
PAINT SKYBLUE (-3100 2350);
DISPLAY INVISIBLE (-3100 2350);
FORCEPROP 2 LAST CDS_LIB mstr_symbols
J 1
(-3100 2350);
PAINT ORANGE (-3100 2350);
DISPLAY INVISIBLE (-3100 2350);
FORCEPROP 1 LAST SIZE 1B
J 0
(-3025 2300);
DISPLAY 1.170213 (-3025 2300);
PAINT GREEN (-3025 2300);
DISPLAY INVISIBLE (-3025 2300);
FORCEPROP 1 LAST BODY_TYPE PLUMBING
J 0
(-3145 2307);
DISPLAY 0.340426 (-3145 2307);
PAINT GREEN (-3145 2307);
DISPLAY INVISIBLE (-3145 2307);
FORCEPROP 1 LAST PATH I27
J 0
(-3025 2350);
DISPLAY 0.872340 (-3025 2350);
PAINT AQUA (-3025 2350);
DISPLAY INVISIBLE (-3025 2350);
FORCEPROP 1 LAST HDL_POWER GND
J 0
(-3100 2500);
DISPLAY 0.936170 (-3100 2500);
PAINT GREEN (-3100 2500);
DISPLAY INVISIBLE (-3100 2500);
FORCEADD FET_N_DUAL..5
(-3100 2625);
FORCEPROP 1 LAST LOCATION Q2U1
J 0
(-2900 2775);
DISPLAY 0.617021 (-2900 2775);
PAINT AQUA (-2900 2775);
FORCEPROP 1 LAST PART_NUMBER E40049-001
J 0
(-2900 2625);
DISPLAY 0.617021 (-2900 2625);
PAINT BLUE (-2900 2625);
FORCEPROP 1 LAST VALUE NTJD4001N
J 0
(-2900 2725);
DISPLAY 0.617021 (-2900 2725);
PAINT SKYBLUE (-2900 2725);
FORCEPROP 1 LAST MATERIAL FET
J 0
(-2900 2675);
DISPLAY 0.617021 (-2900 2675);
PAINT SKYBLUE (-2900 2675);
FORCEPROP 1 LASTPIN (-3100 2425) $PN 1
J 2
(-3042 2425);
DISPLAY 0.617021 (-3042 2425);
PAINT MONO (-3042 2425);
FORCEPROP 1 LASTPIN (-3300 2525) $PN 2
J 2
(-3297 2540);
DISPLAY 0.617021 (-3297 2540);
PAINT MONO (-3297 2540);
FORCEPROP 1 LASTPIN (-3100 2825) $PN 6
J 2
(-3047 2790);
DISPLAY 0.617021 (-3047 2790);
PAINT MONO (-3047 2790);
FORCEPROP 1 LAST PACK_TYPE SMLF
J 0
(-2900 2475);
PAINT SKYBLUE (-2900 2475);
DISPLAY INVISIBLE (-2900 2475);
FORCEPROP 2 LAST BOM_COST PROC_SIDEBAND
J 0
(-3100 2625);
PAINT MONO (-3100 2625);
DISPLAY INVISIBLE (-3100 2625);
FORCEPROP 2 LAST SEC_TYPE SMLF
J 1
(-2900 2725);
PAINT MONO (-2900 2725);
DISPLAY INVISIBLE (-2900 2725);
FORCEPROP 2 LAST CDS_LIB mstr_discrete
J 1
(-3100 2625);
PAINT ORANGE (-3100 2625);
DISPLAY INVISIBLE (-3100 2625);
FORCEPROP 2 LAST SEC 1
J 1
(-2900 2725);
PAINT MONO (-2900 2725);
DISPLAY INVISIBLE (-2900 2725);
FORCEPROP 2 LAST CDS_LOCATION Q2U1
J 0
(-2900 2775);
DISPLAY 0.617021 (-2900 2775);
PAINT AQUA (-2900 2775);
DISPLAY INVISIBLE (-2900 2775);
FORCEPROP 1 LAST PATH I28
J 0
(-2900 2675);
DISPLAY 0.978723 (-2900 2675);
PAINT BLUE (-2900 2675);
DISPLAY INVISIBLE (-2900 2675);
FORCEPROP 2 LAST ROOM PROC_SIDEBAND
J 1
(-2900 2875);
PAINT ORANGE (-2900 2875);
DISPLAY INVISIBLE (-2900 2875);
FORCEADD GND..1
(-3100 1675);
FORCEPROP 3 LASTPIN (-3100 1725) SIG_NAME GND\g
J 0
(-3090 1735);
DISPLAY 0.659574 (-3090 1735);
PAINT MONO (-3090 1735);
DISPLAY INVISIBLE (-3090 1735);
FORCEPROP 1 LAST VOLTAGE 0
J 0
(-3100 1675);
PAINT SKYBLUE (-3100 1675);
DISPLAY INVISIBLE (-3100 1675);
FORCEPROP 2 LAST CDS_LIB mstr_symbols
J 1
(-3100 1675);
PAINT ORANGE (-3100 1675);
DISPLAY INVISIBLE (-3100 1675);
FORCEPROP 1 LAST SIZE 1B
J 0
(-3025 1625);
DISPLAY 1.170213 (-3025 1625);
PAINT GREEN (-3025 1625);
DISPLAY INVISIBLE (-3025 1625);
FORCEPROP 1 LAST BODY_TYPE PLUMBING
J 0
(-3145 1632);
DISPLAY 0.340426 (-3145 1632);
PAINT GREEN (-3145 1632);
DISPLAY INVISIBLE (-3145 1632);
FORCEPROP 1 LAST PATH I29
J 0
(-3025 1675);
DISPLAY 0.872340 (-3025 1675);
PAINT AQUA (-3025 1675);
DISPLAY INVISIBLE (-3025 1675);
FORCEPROP 1 LAST HDL_POWER GND
J 0
(-3100 1825);
DISPLAY 1.170213 (-3100 1825);
PAINT GREEN (-3100 1825);
DISPLAY INVISIBLE (-3100 1825);
FORCEADD GND..1
(-3100 1025);
FORCEPROP 3 LASTPIN (-3100 1075) SIG_NAME GND\g
J 0
(-3090 1085);
DISPLAY 0.659574 (-3090 1085);
PAINT MONO (-3090 1085);
DISPLAY INVISIBLE (-3090 1085);
FORCEPROP 1 LAST VOLTAGE 0
J 0
(-3100 1025);
PAINT SKYBLUE (-3100 1025);
DISPLAY INVISIBLE (-3100 1025);
FORCEPROP 2 LAST CDS_LIB mstr_symbols
J 1
(-3100 1025);
PAINT ORANGE (-3100 1025);
DISPLAY INVISIBLE (-3100 1025);
FORCEPROP 1 LAST SIZE 1B
J 0
(-3025 975);
DISPLAY 1.170213 (-3025 975);
PAINT GREEN (-3025 975);
DISPLAY INVISIBLE (-3025 975);
FORCEPROP 1 LAST BODY_TYPE PLUMBING
J 0
(-3145 982);
DISPLAY 0.340426 (-3145 982);
PAINT GREEN (-3145 982);
DISPLAY INVISIBLE (-3145 982);
FORCEPROP 1 LAST PATH I30
J 0
(-3025 1025);
DISPLAY 0.872340 (-3025 1025);
PAINT AQUA (-3025 1025);
DISPLAY INVISIBLE (-3025 1025);
FORCEPROP 1 LAST HDL_POWER GND
J 0
(-3100 1175);
DISPLAY 1.170213 (-3100 1175);
PAINT GREEN (-3100 1175);
DISPLAY INVISIBLE (-3100 1175);
FORCEADD FET_N_DUAL..5
(-3100 1300);
FORCEPROP 1 LAST LOCATION Q4B2
J 0
(-2900 1475);
DISPLAY 0.617021 (-2900 1475);
PAINT AQUA (-2900 1475);
FORCEPROP 1 LAST PART_NUMBER E40049-001
J 0
(-2900 1325);
DISPLAY 0.617021 (-2900 1325);
PAINT BLUE (-2900 1325);
FORCEPROP 1 LAST VALUE NTJD4001N
J 0
(-2900 1425);
DISPLAY 0.617021 (-2900 1425);
PAINT SKYBLUE (-2900 1425);
FORCEPROP 1 LAST MATERIAL FET
J 0
(-2900 1375);
DISPLAY 0.617021 (-2900 1375);
PAINT SKYBLUE (-2900 1375);
FORCEPROP 1 LASTPIN (-3100 1100) $PN 1
J 2
(-3042 1100);
DISPLAY 0.617021 (-3042 1100);
PAINT MONO (-3042 1100);
FORCEPROP 1 LASTPIN (-3300 1200) $PN 2
J 2
(-3297 1215);
DISPLAY 0.617021 (-3297 1215);
PAINT MONO (-3297 1215);
FORCEPROP 1 LASTPIN (-3100 1500) $PN 6
J 2
(-3047 1465);
DISPLAY 0.617021 (-3047 1465);
PAINT MONO (-3047 1465);
FORCEPROP 1 LAST PACK_TYPE SMLF
J 0
(-2900 1150);
PAINT SKYBLUE (-2900 1150);
DISPLAY INVISIBLE (-2900 1150);
FORCEPROP 2 LAST SEC_TYPE SMLF
J 1
(-2900 1400);
PAINT MONO (-2900 1400);
DISPLAY INVISIBLE (-2900 1400);
FORCEPROP 2 LAST CDS_LIB mstr_discrete
J 1
(-3100 1300);
PAINT ORANGE (-3100 1300);
DISPLAY INVISIBLE (-3100 1300);
FORCEPROP 2 LAST BOM_COST PROC_SIDEBAND
J 0
(-3100 1300);
PAINT MONO (-3100 1300);
DISPLAY INVISIBLE (-3100 1300);
FORCEPROP 2 LAST SEC 1
J 1
(-2900 1400);
PAINT MONO (-2900 1400);
DISPLAY INVISIBLE (-2900 1400);
FORCEPROP 2 LAST CDS_LOCATION Q4B2
J 0
(-2900 1475);
DISPLAY 0.617021 (-2900 1475);
PAINT AQUA (-2900 1475);
DISPLAY INVISIBLE (-2900 1475);
FORCEPROP 1 LAST PATH I32
J 0
(-2900 1350);
DISPLAY 0.978723 (-2900 1350);
PAINT BLUE (-2900 1350);
DISPLAY INVISIBLE (-2900 1350);
FORCEPROP 2 LAST ROOM PROC_SIDEBAND
J 1
(-2900 1575);
PAINT ORANGE (-2900 1575);
DISPLAY INVISIBLE (-2900 1575);
FORCEADD FET_N_DUAL..5
(-3100 700);
FORCEPROP 1 LAST LOCATION Q4B2
J 0
(-2900 875);
DISPLAY 0.617021 (-2900 875);
PAINT AQUA (-2900 875);
FORCEPROP 1 LAST PART_NUMBER E40049-001
J 0
(-2900 725);
DISPLAY 0.617021 (-2900 725);
PAINT BLUE (-2900 725);
FORCEPROP 1 LAST VALUE NTJD4001N
J 0
(-2900 825);
DISPLAY 0.617021 (-2900 825);
PAINT SKYBLUE (-2900 825);
FORCEPROP 1 LAST MATERIAL FET
J 0
(-2900 775);
DISPLAY 0.617021 (-2900 775);
PAINT SKYBLUE (-2900 775);
FORCEPROP 1 LASTPIN (-3100 500) $PN 4
J 2
(-3042 500);
DISPLAY 0.617021 (-3042 500);
PAINT MONO (-3042 500);
FORCEPROP 1 LASTPIN (-3300 600) $PN 5
J 2
(-3297 615);
DISPLAY 0.617021 (-3297 615);
PAINT MONO (-3297 615);
FORCEPROP 1 LASTPIN (-3100 900) $PN 3
J 2
(-3047 865);
DISPLAY 0.617021 (-3047 865);
PAINT MONO (-3047 865);
FORCEPROP 1 LAST PACK_TYPE SMLF
J 0
(-2900 550);
PAINT SKYBLUE (-2900 550);
DISPLAY INVISIBLE (-2900 550);
FORCEPROP 2 LAST SEC_TYPE SMLF
J 1
(-2900 800);
PAINT MONO (-2900 800);
DISPLAY INVISIBLE (-2900 800);
FORCEPROP 2 LAST CDS_LIB mstr_discrete
J 1
(-3100 700);
PAINT ORANGE (-3100 700);
DISPLAY INVISIBLE (-3100 700);
FORCEPROP 2 LAST BOM_COST PROC_SIDEBAND
J 0
(-3100 700);
PAINT MONO (-3100 700);
DISPLAY INVISIBLE (-3100 700);
FORCEPROP 2 LAST SEC 2
J 1
(-2900 800);
PAINT MONO (-2900 800);
DISPLAY INVISIBLE (-2900 800);
FORCEPROP 2 LAST CDS_LOCATION Q4B2
J 0
(-2900 875);
DISPLAY 0.617021 (-2900 875);
PAINT AQUA (-2900 875);
DISPLAY INVISIBLE (-2900 875);
FORCEPROP 1 LAST PATH I33
J 0
(-2900 750);
DISPLAY 0.978723 (-2900 750);
PAINT BLUE (-2900 750);
DISPLAY INVISIBLE (-2900 750);
FORCEPROP 2 LAST ROOM PROC_SIDEBAND
J 1
(-2900 975);
PAINT ORANGE (-2900 975);
DISPLAY INVISIBLE (-2900 975);
FORCEADD FET_N_DUAL..5
(-3100 3275);
FORCEPROP 1 LAST LOCATION Q7E3
J 0
(-2900 3275);
DISPLAY 0.617021 (-2900 3275);
PAINT AQUA (-2900 3275);
FORCEPROP 1 LAST PART_NUMBER E40049-001
J 0
(-2900 3225);
DISPLAY 0.617021 (-2900 3225);
PAINT BLUE (-2900 3225);
FORCEPROP 1 LAST VALUE NTJD4001N
J 0
(-2900 3375);
DISPLAY 0.617021 (-2900 3375);
PAINT SKYBLUE (-2900 3375);
FORCEPROP 1 LAST MATERIAL FET
J 0
(-2900 3325);
DISPLAY 0.617021 (-2900 3325);
PAINT SKYBLUE (-2900 3325);
FORCEPROP 1 LASTPIN (-3100 3075) $PN 4
J 2
(-3042 3075);
DISPLAY 0.617021 (-3042 3075);
PAINT WHITE (-3042 3075);
FORCEPROP 1 LASTPIN (-3300 3175) $PN 5
J 2
(-3297 3190);
DISPLAY 0.617021 (-3297 3190);
PAINT WHITE (-3297 3190);
FORCEPROP 1 LASTPIN (-3100 3475) $PN 3
J 2
(-3047 3440);
DISPLAY 0.617021 (-3047 3440);
PAINT WHITE (-3047 3440);
FORCEPROP 1 LAST PACK_TYPE SMLF
J 0
(-2900 3125);
PAINT SKYBLUE (-2900 3125);
DISPLAY INVISIBLE (-2900 3125);
FORCEPROP 2 LAST SEC_TYPE SMLF
J 0
(-2900 3425);
DISPLAY 1.021277 (-2900 3425);
PAINT ORANGE (-2900 3425);
DISPLAY INVISIBLE (-2900 3425);
FORCEPROP 2 LAST CDS_LIB mstr_discrete
J 0
(-3100 3275);
PAINT ORANGE (-3100 3275);
DISPLAY INVISIBLE (-3100 3275);
FORCEPROP 2 LAST BOM_COST PROC_SIDEBAND
J 0
(-3100 3275);
PAINT MONO (-3100 3275);
DISPLAY INVISIBLE (-3100 3275);
FORCEPROP 2 LAST SEC 2
J 0
(-2900 3425);
DISPLAY 0.680851 (-2900 3425);
PAINT MONO (-2900 3425);
DISPLAY INVISIBLE (-2900 3425);
FORCEPROP 2 LAST CDS_LOCATION Q7E3
J 0
(-2900 3275);
DISPLAY 0.617021 (-2900 3275);
PAINT AQUA (-2900 3275);
DISPLAY INVISIBLE (-2900 3275);
FORCEPROP 1 LAST PATH I51
J 0
(-2900 3325);
DISPLAY 0.978723 (-2900 3325);
PAINT BLUE (-2900 3325);
DISPLAY INVISIBLE (-2900 3325);
FORCEPROP 2 LAST ROOM PROC_SIDEBAND
J 1
(-2900 3525);
PAINT ORANGE (-2900 3525);
DISPLAY INVISIBLE (-2900 3525);
FORCEADD FET_N_DUAL..5
(-3100 3950);
FORCEPROP 1 LAST LOCATION Q7E3
J 0
(-2900 3950);
DISPLAY 0.617021 (-2900 3950);
PAINT AQUA (-2900 3950);
FORCEPROP 1 LAST PART_NUMBER E40049-001
J 0
(-2900 3900);
DISPLAY 0.617021 (-2900 3900);
PAINT BLUE (-2900 3900);
FORCEPROP 1 LAST VALUE NTJD4001N
J 0
(-2900 4050);
DISPLAY 0.617021 (-2900 4050);
PAINT SKYBLUE (-2900 4050);
FORCEPROP 1 LAST MATERIAL FET
J 0
(-2900 4000);
DISPLAY 0.617021 (-2900 4000);
PAINT SKYBLUE (-2900 4000);
FORCEPROP 1 LASTPIN (-3100 3750) $PN 1
J 2
(-3042 3750);
DISPLAY 0.617021 (-3042 3750);
PAINT WHITE (-3042 3750);
FORCEPROP 1 LASTPIN (-3300 3850) $PN 2
J 2
(-3297 3865);
DISPLAY 0.617021 (-3297 3865);
PAINT WHITE (-3297 3865);
FORCEPROP 1 LASTPIN (-3100 4150) $PN 6
J 2
(-3047 4115);
DISPLAY 0.617021 (-3047 4115);
PAINT WHITE (-3047 4115);
FORCEPROP 1 LAST PACK_TYPE SMLF
J 0
(-2900 3800);
PAINT SKYBLUE (-2900 3800);
DISPLAY INVISIBLE (-2900 3800);
FORCEPROP 2 LAST SEC_TYPE SMLF
J 0
(-2900 4100);
DISPLAY 1.021277 (-2900 4100);
PAINT ORANGE (-2900 4100);
DISPLAY INVISIBLE (-2900 4100);
FORCEPROP 2 LAST CDS_LIB mstr_discrete
J 0
(-3100 3950);
PAINT ORANGE (-3100 3950);
DISPLAY INVISIBLE (-3100 3950);
FORCEPROP 2 LAST BOM_COST PROC_SIDEBAND
J 0
(-3100 3950);
PAINT MONO (-3100 3950);
DISPLAY INVISIBLE (-3100 3950);
FORCEPROP 2 LAST SEC 1
J 0
(-2900 4100);
DISPLAY 0.680851 (-2900 4100);
PAINT MONO (-2900 4100);
DISPLAY INVISIBLE (-2900 4100);
FORCEPROP 2 LAST CDS_LOCATION Q7E3
J 0
(-2900 3950);
DISPLAY 0.617021 (-2900 3950);
PAINT AQUA (-2900 3950);
DISPLAY INVISIBLE (-2900 3950);
FORCEPROP 1 LAST PATH I52
J 0
(-2900 4000);
DISPLAY 0.978723 (-2900 4000);
PAINT BLUE (-2900 4000);
DISPLAY INVISIBLE (-2900 4000);
FORCEPROP 2 LAST ROOM PROC_SIDEBAND
J 1
(-2900 4200);
PAINT ORANGE (-2900 4200);
DISPLAY INVISIBLE (-2900 4200);
FORCEADD OFFPAGE..5
R 2
(3655 5025);
FORCEPROP 2 LAST $XR0 21 
J 0
(3844 5025);
DISPLAY 0.638298 (3844 5025);
PAINT MONO (3844 5025);
FORCEPROP 2 LAST $XR1 95 
J 0
(3934 5025);
DISPLAY 0.638298 (3934 5025);
PAINT MONO (3934 5025);
FORCEPROP 2 LAST $XR2 93 
J 0
(4024 5025);
DISPLAY 0.638298 (4024 5025);
PAINT MONO (4024 5025);
FORCEPROP 2 LAST CDS_LIB mstr_standard
J 0
(3655 5025);
DISPLAY 1.340426 (3655 5025);
PAINT ORANGE (3655 5025);
DISPLAY INVISIBLE (3655 5025);
FORCEPROP 1 LAST OFFPAGE TRUE
J 2
(3330 4900);
DISPLAY 0.978723 (3330 4900);
PAINT GREEN (3330 4900);
DISPLAY INVISIBLE (3330 4900);
FORCEPROP 1 LAST COMMENT_BODY TRUE
J 2
(3555 4950);
DISPLAY 0.978723 (3555 4950);
PAINT GREEN (3555 4950);
DISPLAY INVISIBLE (3555 4950);
FORCEPROP 2 LAST PATH I58
J 0
(4000 5075);
DISPLAY 1.021277 (4000 5075);
PAINT ORANGE (4000 5075);
DISPLAY INVISIBLE (4000 5075);
FORCEADD FET_N_DUAL..5
(3050 4725);
FORCEPROP 1 LAST LOCATION Q7E5
J 0
(3250 4725);
DISPLAY 0.617021 (3250 4725);
PAINT AQUA (3250 4725);
FORCEPROP 1 LAST PART_NUMBER E40049-001
J 0
(3250 4525);
DISPLAY 0.617021 (3250 4525);
PAINT BLUE (3250 4525);
FORCEPROP 1 LAST VALUE NTJD4001N
J 0
(3250 4675);
DISPLAY 0.617021 (3250 4675);
PAINT SKYBLUE (3250 4675);
FORCEPROP 1 LAST MATERIAL FET
J 0
(3250 4625);
DISPLAY 0.617021 (3250 4625);
PAINT SKYBLUE (3250 4625);
FORCEPROP 1 LASTPIN (3050 4525) $PN 4
J 2
(3108 4525);
DISPLAY 0.617021 (3108 4525);
PAINT WHITE (3108 4525);
FORCEPROP 1 LASTPIN (2850 4625) $PN 5
J 2
(2853 4640);
DISPLAY 0.617021 (2853 4640);
PAINT WHITE (2853 4640);
FORCEPROP 1 LASTPIN (3050 4925) $PN 3
J 2
(3103 4890);
DISPLAY 0.617021 (3103 4890);
PAINT WHITE (3103 4890);
FORCEPROP 1 LAST PACK_TYPE SMLF
J 0
(3250 4575);
DISPLAY 0.978723 (3250 4575);
PAINT SKYBLUE (3250 4575);
DISPLAY INVISIBLE (3250 4575);
FORCEPROP 2 LAST SEC_TYPE SMLF
J 0
(3250 4825);
DISPLAY 1.021277 (3250 4825);
PAINT ORANGE (3250 4825);
DISPLAY INVISIBLE (3250 4825);
FORCEPROP 2 LAST CDS_LIB mstr_discrete
J 0
(3050 4725);
PAINT ORANGE (3050 4725);
DISPLAY INVISIBLE (3050 4725);
FORCEPROP 2 LAST BOM_COST PROC_SIDEBAND
J 0
(3050 4725);
PAINT MONO (3050 4725);
DISPLAY INVISIBLE (3050 4725);
FORCEPROP 2 LAST SEC 2
J 0
(3250 4825);
DISPLAY 0.680851 (3250 4825);
PAINT MONO (3250 4825);
DISPLAY INVISIBLE (3250 4825);
FORCEPROP 2 LAST CDS_LOCATION Q7E5
J 0
(3250 4725);
DISPLAY 0.617021 (3250 4725);
PAINT AQUA (3250 4725);
DISPLAY INVISIBLE (3250 4725);
FORCEPROP 1 LAST PATH I59
J 0
(3250 4775);
DISPLAY 0.978723 (3250 4775);
PAINT BLUE (3250 4775);
DISPLAY INVISIBLE (3250 4775);
FORCEPROP 2 LAST ROOM HOT_EVENTS
J 0
(3250 4825);
PAINT ORANGE (3250 4825);
DISPLAY INVISIBLE (3250 4825);
FORCEADD OFFPAGE..2
(-700 4200);
FORCEPROP 2 LAST $XR0 21 
J 0
(-511 4200);
DISPLAY 0.638298 (-511 4200);
PAINT MONO (-511 4200);
FORCEPROP 2 LAST $XR1 95 
J 0
(-421 4200);
DISPLAY 0.638298 (-421 4200);
PAINT MONO (-421 4200);
FORCEPROP 2 LAST $XR2 93 
J 0
(-331 4200);
DISPLAY 0.638298 (-331 4200);
PAINT MONO (-331 4200);
FORCEPROP 2 LAST ROOM SMART_CLST
J 0
(-950 4275);
DISPLAY 1.361702 (-950 4275);
PAINT ORANGE (-950 4275);
DISPLAY INVISIBLE (-950 4275);
FORCEPROP 2 LAST CDS_LIB mstr_standard
J 0
(-700 4200);
DISPLAY 1.361702 (-700 4200);
PAINT ORANGE (-700 4200);
DISPLAY INVISIBLE (-700 4200);
FORCEPROP 1 LAST OFFPAGE TRUE
J 0
(-375 4075);
PAINT GREEN (-375 4075);
DISPLAY INVISIBLE (-375 4075);
FORCEPROP 1 LAST COMMENT_BODY TRUE
J 0
(-745 4105);
DISPLAY 1.170213 (-745 4105);
PAINT GREEN (-745 4105);
DISPLAY INVISIBLE (-745 4105);
FORCEPROP 2 LAST PATH I6
J 0
(-325 4250);
DISPLAY 1.021277 (-325 4250);
PAINT ORANGE (-325 4250);
DISPLAY INVISIBLE (-325 4250);
FORCEADD GND..1
(3050 4225);
FORCEPROP 3 LASTPIN (3050 4275) SIG_NAME GND\g
J 0
(3060 4285);
DISPLAY 0.659574 (3060 4285);
PAINT MONO (3060 4285);
DISPLAY INVISIBLE (3060 4285);
FORCEPROP 1 LAST VOLTAGE 0.0V
J 0
(3005 4182);
DISPLAY 0.340426 (3005 4182);
PAINT SKYBLUE (3005 4182);
DISPLAY INVISIBLE (3005 4182);
FORCEPROP 1 LAST SIZE 1B
J 0
(3125 4175);
DISPLAY 1.170213 (3125 4175);
PAINT GREEN (3125 4175);
DISPLAY INVISIBLE (3125 4175);
FORCEPROP 2 LAST CDS_LIB mstr_symbols
J 0
(3050 4225);
PAINT ORANGE (3050 4225);
DISPLAY INVISIBLE (3050 4225);
FORCEPROP 1 LAST BODY_TYPE PLUMBING
J 0
(3005 4182);
DISPLAY 0.340426 (3005 4182);
PAINT GREEN (3005 4182);
DISPLAY INVISIBLE (3005 4182);
FORCEPROP 1 LAST PATH I60
J 0
(3125 4225);
DISPLAY 0.872340 (3125 4225);
PAINT AQUA (3125 4225);
DISPLAY INVISIBLE (3125 4225);
FORCEPROP 2 LAST ROOM PROCHOT_MEMHOT_ISO
J 0
(2675 4300);
PAINT ORANGE (2675 4300);
DISPLAY INVISIBLE (2675 4300);
FORCEPROP 1 LAST HDL_POWER GND
J 0
(3050 4375);
DISPLAY 1.170213 (3050 4375);
PAINT GREEN (3050 4375);
DISPLAY INVISIBLE (3050 4375);
FORCEADD P3V3..1
(2475 5050);
FORCEPROP 3 LASTPIN (2475 5000) SIG_NAME P3V3\g
J 0
(2485 5010);
DISPLAY 0.659574 (2485 5010);
PAINT MONO (2485 5010);
DISPLAY INVISIBLE (2485 5010);
FORCEPROP 1 LAST VOLTAGE 3.3V
J 0
(2430 5007);
DISPLAY 0.340426 (2430 5007);
PAINT SKYBLUE (2430 5007);
DISPLAY INVISIBLE (2430 5007);
FORCEPROP 2 LAST CDS_LIB mstr_symbols
J 0
(2475 5050);
PAINT ORANGE (2475 5050);
DISPLAY INVISIBLE (2475 5050);
FORCEPROP 1 LAST SIZE 1B
J 0
(2520 5072);
DISPLAY 0.446809 (2520 5072);
PAINT GREEN (2520 5072);
DISPLAY INVISIBLE (2520 5072);
FORCEPROP 1 LAST BODY_TYPE PLUMBING
J 0
(2430 5007);
DISPLAY 0.446809 (2430 5007);
PAINT GREEN (2430 5007);
DISPLAY INVISIBLE (2430 5007);
FORCEPROP 1 LAST PATH I61
J 0
(2520 5052);
DISPLAY 0.340426 (2520 5052);
PAINT GREEN (2520 5052);
DISPLAY INVISIBLE (2520 5052);
FORCEPROP 2 LAST ROOM PROCHOT_MEMHOT_ISO
J 0
(2275 5150);
DISPLAY 1.340426 (2275 5150);
PAINT ORANGE (2275 5150);
DISPLAY INVISIBLE (2275 5150);
FORCEPROP 1 LAST HDL_POWER P3V3
J 0
(2150 4925);
DISPLAY 1.170213 (2150 4925);
PAINT GREEN (2150 4925);
DISPLAY INVISIBLE (2150 4925);
FORCEADD RES..2
R 2
(2475 4800);
FORCEPROP 1 LAST LOCATION R7E10
J 2
(2430 4900);
DISPLAY 0.617021 (2430 4900);
PAINT AQUA (2430 4900);
FORCEPROP 1 LAST PART_NUMBER G21796-072
R 1
J 2
(2535 5000);
DISPLAY 0.617021 (2535 5000);
PAINT BLUE (2535 5000);
FORCEPROP 1 LAST VALUE 4.75K
J 2
(2430 4850);
DISPLAY 0.617021 (2430 4850);
PAINT SKYBLUE (2430 4850);
FORCEPROP 1 LAST TOLERANCE 1%
J 2
(2430 4800);
DISPLAY 0.617021 (2430 4800);
PAINT SKYBLUE (2430 4800);
FORCEPROP 1 LAST PACK_TYPE 0402
J 2
(2435 4700);
DISPLAY 0.617021 (2435 4700);
PAINT SKYBLUE (2435 4700);
FORCEPROP 1 LAST WATTAGE 1/16W
J 2
(2435 4750);
DISPLAY 0.617021 (2435 4750);
PAINT SKYBLUE (2435 4750);
FORCEPROP 1 LASTPIN (2475 4700) $PN 2
J 2
(2470 4710);
DISPLAY 0.617021 (2470 4710);
PAINT WHITE (2470 4710);
FORCEPROP 1 LASTPIN (2475 4900) $PN 1
J 2
(2470 4862);
DISPLAY 0.617021 (2470 4862);
PAINT WHITE (2470 4862);
FORCEPROP 1 LAST MATERIAL CHIP
J 2
(2435 4725);
PAINT SKYBLUE (2435 4725);
DISPLAY INVISIBLE (2435 4725);
FORCEPROP 2 LAST CDS_LIB mstr_discrete
J 2
(2475 4800);
DISPLAY 1.340426 (2475 4800);
PAINT ORANGE (2475 4800);
DISPLAY INVISIBLE (2475 4800);
FORCEPROP 2 LAST BOM_COST PROC_SIDEBAND
J 2
(2475 4800);
PAINT MONO (2475 4800);
DISPLAY INVISIBLE (2475 4800);
FORCEPROP 2 LAST CDS_SEC 1
J 1
(2425 5025);
PAINT MONO (2425 5025);
DISPLAY INVISIBLE (2425 5025);
FORCEPROP 2 LAST $SEC 1
J 1
(2425 5025);
PAINT MONO (2425 5025);
DISPLAY INVISIBLE (2425 5025);
FORCEPROP 2 LAST CDS_LOCATION R7E10
J 2
(2430 4900);
DISPLAY 0.617021 (2430 4900);
PAINT AQUA (2430 4900);
DISPLAY INVISIBLE (2430 4900);
FORCEPROP 1 LAST PATH I62
J 2
(2425 4975);
DISPLAY 0.978723 (2425 4975);
PAINT WHITE (2425 4975);
DISPLAY INVISIBLE (2425 4975);
FORCEPROP 2 LAST ROOM HOT_EVENTS
J 2
(2425 4975);
PAINT PEACH (2425 4975);
DISPLAY INVISIBLE (2425 4975);
FORCEADD GND..1
(2475 4025);
FORCEPROP 3 LASTPIN (2475 4075) SIG_NAME GND\g
J 0
(2485 4085);
DISPLAY 0.659574 (2485 4085);
PAINT MONO (2485 4085);
DISPLAY INVISIBLE (2485 4085);
FORCEPROP 1 LAST VOLTAGE 0.0V
J 0
(2430 3982);
DISPLAY 0.340426 (2430 3982);
PAINT SKYBLUE (2430 3982);
DISPLAY INVISIBLE (2430 3982);
FORCEPROP 1 LAST SIZE 1B
J 0
(2550 3975);
DISPLAY 1.170213 (2550 3975);
PAINT GREEN (2550 3975);
DISPLAY INVISIBLE (2550 3975);
FORCEPROP 2 LAST CDS_LIB mstr_symbols
J 0
(2475 4025);
PAINT ORANGE (2475 4025);
DISPLAY INVISIBLE (2475 4025);
FORCEPROP 1 LAST BODY_TYPE PLUMBING
J 0
(2430 3982);
DISPLAY 0.340426 (2430 3982);
PAINT GREEN (2430 3982);
DISPLAY INVISIBLE (2430 3982);
FORCEPROP 1 LAST PATH I63
J 0
(2550 4025);
DISPLAY 0.872340 (2550 4025);
PAINT AQUA (2550 4025);
DISPLAY INVISIBLE (2550 4025);
FORCEPROP 2 LAST ROOM PROCHOT_MEMHOT_ISO
J 0
(2100 4100);
PAINT ORANGE (2100 4100);
DISPLAY INVISIBLE (2100 4100);
FORCEPROP 1 LAST HDL_POWER GND
J 0
(2475 4175);
DISPLAY 1.170213 (2475 4175);
PAINT GREEN (2475 4175);
DISPLAY INVISIBLE (2475 4175);
FORCEADD OFFPAGE..1
(500 4175);
FORCEPROP 2 LAST $XR0 201 
J 0
(248 4175);
DISPLAY 0.638298 (248 4175);
PAINT MONO (248 4175);
FORCEPROP 2 LAST $XR1 120 
J 0
(128 4175);
DISPLAY 0.638298 (128 4175);
PAINT MONO (128 4175);
FORCEPROP 2 LAST $XR2 145 
J 0
(8 4175);
DISPLAY 0.638298 (8 4175);
PAINT MONO (8 4175);
FORCEPROP 2 LAST ROOM PROCHOT_MEMHOT_ISO
J 0
(250 4225);
DISPLAY 0.978723 (250 4225);
PAINT ORANGE (250 4225);
DISPLAY INVISIBLE (250 4225);
FORCEPROP 2 LAST CDS_LIB mstr_standard
J 0
(500 4175);
DISPLAY 1.340426 (500 4175);
PAINT ORANGE (500 4175);
DISPLAY INVISIBLE (500 4175);
FORCEPROP 1 LAST OFFPAGE TRUE
J 0
(825 4050);
DISPLAY 0.978723 (825 4050);
PAINT GREEN (825 4050);
DISPLAY INVISIBLE (825 4050);
FORCEPROP 1 LAST COMMENT_BODY TRUE
J 0
(625 4075);
DISPLAY 0.978723 (625 4075);
PAINT PEACH (625 4075);
DISPLAY INVISIBLE (625 4075);
FORCEPROP 2 LAST PATH I66
J 0
(200 4225);
DISPLAY 1.021277 (200 4225);
PAINT ORANGE (200 4225);
DISPLAY INVISIBLE (200 4225);
FORCEADD OFFPAGE..1
(500 4275);
FORCEPROP 2 LAST $XR0 201 
J 0
(248 4275);
DISPLAY 0.638298 (248 4275);
PAINT MONO (248 4275);
FORCEPROP 2 LAST CDS_LIB mstr_standard
J 0
(500 4275);
DISPLAY 1.340426 (500 4275);
PAINT ORANGE (500 4275);
DISPLAY INVISIBLE (500 4275);
FORCEPROP 2 LAST ROOM PROCHOT_MEMHOT_ISO
J 0
(250 4325);
DISPLAY 0.978723 (250 4325);
PAINT ORANGE (250 4325);
DISPLAY INVISIBLE (250 4325);
FORCEPROP 1 LAST OFFPAGE TRUE
J 0
(825 4150);
DISPLAY 0.978723 (825 4150);
PAINT GREEN (825 4150);
DISPLAY INVISIBLE (825 4150);
FORCEPROP 1 LAST COMMENT_BODY TRUE
J 0
(625 4175);
DISPLAY 0.978723 (625 4175);
PAINT PEACH (625 4175);
DISPLAY INVISIBLE (625 4175);
FORCEPROP 2 LAST PATH I67
J 0
(200 4325);
DISPLAY 1.021277 (200 4325);
PAINT ORANGE (200 4325);
DISPLAY INVISIBLE (200 4325);
FORCEADD OFFPAGE..5
R 2
(3755 3575);
FORCEPROP 2 LAST $XR0 55 
J 0
(3944 3575);
DISPLAY 0.638298 (3944 3575);
PAINT MONO (3944 3575);
FORCEPROP 2 LAST $XR1 95 
J 0
(4034 3575);
DISPLAY 0.638298 (4034 3575);
PAINT MONO (4034 3575);
FORCEPROP 2 LAST $XR2 93 
J 0
(4124 3575);
DISPLAY 0.638298 (4124 3575);
PAINT MONO (4124 3575);
FORCEPROP 2 LAST CDS_LIB mstr_standard
J 0
(3755 3575);
DISPLAY 1.340426 (3755 3575);
PAINT ORANGE (3755 3575);
DISPLAY INVISIBLE (3755 3575);
FORCEPROP 1 LAST OFFPAGE TRUE
J 2
(3430 3450);
DISPLAY 0.978723 (3430 3450);
PAINT GREEN (3430 3450);
DISPLAY INVISIBLE (3430 3450);
FORCEPROP 1 LAST COMMENT_BODY TRUE
J 2
(3655 3500);
DISPLAY 0.978723 (3655 3500);
PAINT GREEN (3655 3500);
DISPLAY INVISIBLE (3655 3500);
FORCEPROP 2 LAST PATH I68
J 0
(4100 3625);
DISPLAY 1.021277 (4100 3625);
PAINT ORANGE (4100 3625);
DISPLAY INVISIBLE (4100 3625);
FORCEADD FET_N_DUAL..5
(3150 3275);
FORCEPROP 1 LAST LOCATION Q7E6
J 0
(3350 3275);
DISPLAY 0.617021 (3350 3275);
PAINT AQUA (3350 3275);
FORCEPROP 1 LAST PART_NUMBER E40049-001
J 0
(3350 3075);
DISPLAY 0.617021 (3350 3075);
PAINT BLUE (3350 3075);
FORCEPROP 1 LAST VALUE NTJD4001N
J 0
(3350 3225);
DISPLAY 0.617021 (3350 3225);
PAINT SKYBLUE (3350 3225);
FORCEPROP 1 LAST MATERIAL FET
J 0
(3350 3175);
DISPLAY 0.617021 (3350 3175);
PAINT SKYBLUE (3350 3175);
FORCEPROP 1 LASTPIN (3150 3075) $PN 4
J 2
(3208 3075);
DISPLAY 0.617021 (3208 3075);
PAINT WHITE (3208 3075);
FORCEPROP 1 LASTPIN (2950 3175) $PN 5
J 2
(2953 3190);
DISPLAY 0.617021 (2953 3190);
PAINT WHITE (2953 3190);
FORCEPROP 1 LASTPIN (3150 3475) $PN 3
J 2
(3203 3440);
DISPLAY 0.617021 (3203 3440);
PAINT WHITE (3203 3440);
FORCEPROP 1 LAST PACK_TYPE SMLF
J 0
(3350 3125);
DISPLAY 0.978723 (3350 3125);
PAINT SKYBLUE (3350 3125);
DISPLAY INVISIBLE (3350 3125);
FORCEPROP 2 LAST SEC_TYPE SMLF
J 0
(3350 3375);
DISPLAY 1.021277 (3350 3375);
PAINT ORANGE (3350 3375);
DISPLAY INVISIBLE (3350 3375);
FORCEPROP 2 LAST CDS_LIB mstr_discrete
J 0
(3150 3275);
PAINT ORANGE (3150 3275);
DISPLAY INVISIBLE (3150 3275);
FORCEPROP 2 LAST BOM_COST PROC_SIDEBAND
J 0
(3150 3275);
PAINT MONO (3150 3275);
DISPLAY INVISIBLE (3150 3275);
FORCEPROP 2 LAST SEC 2
J 0
(3350 3375);
DISPLAY 0.680851 (3350 3375);
PAINT MONO (3350 3375);
DISPLAY INVISIBLE (3350 3375);
FORCEPROP 2 LAST CDS_LOCATION Q7E6
J 0
(3350 3275);
DISPLAY 0.617021 (3350 3275);
PAINT AQUA (3350 3275);
DISPLAY INVISIBLE (3350 3275);
FORCEPROP 1 LAST PATH I69
J 0
(3350 3325);
DISPLAY 0.978723 (3350 3325);
PAINT BLUE (3350 3325);
DISPLAY INVISIBLE (3350 3325);
FORCEPROP 2 LAST ROOM HOT_EVENTS
J 0
(3350 3375);
PAINT ORANGE (3350 3375);
DISPLAY INVISIBLE (3350 3375);
FORCEADD GND..1
(3150 2775);
FORCEPROP 3 LASTPIN (3150 2825) SIG_NAME GND\g
J 0
(3160 2835);
DISPLAY 0.659574 (3160 2835);
PAINT MONO (3160 2835);
DISPLAY INVISIBLE (3160 2835);
FORCEPROP 1 LAST VOLTAGE 0.0V
J 0
(3105 2732);
DISPLAY 0.340426 (3105 2732);
PAINT SKYBLUE (3105 2732);
DISPLAY INVISIBLE (3105 2732);
FORCEPROP 2 LAST CDS_LIB mstr_symbols
J 0
(3150 2775);
PAINT ORANGE (3150 2775);
DISPLAY INVISIBLE (3150 2775);
FORCEPROP 1 LAST SIZE 1B
J 0
(3225 2725);
DISPLAY 1.170213 (3225 2725);
PAINT GREEN (3225 2725);
DISPLAY INVISIBLE (3225 2725);
FORCEPROP 1 LAST BODY_TYPE PLUMBING
J 0
(3105 2732);
DISPLAY 0.340426 (3105 2732);
PAINT GREEN (3105 2732);
DISPLAY INVISIBLE (3105 2732);
FORCEPROP 1 LAST PATH I70
J 0
(3225 2775);
DISPLAY 0.872340 (3225 2775);
PAINT AQUA (3225 2775);
DISPLAY INVISIBLE (3225 2775);
FORCEPROP 2 LAST ROOM PROCHOT_MEMHOT_ISO
J 0
(2775 2850);
PAINT ORANGE (2775 2850);
DISPLAY INVISIBLE (2775 2850);
FORCEPROP 1 LAST HDL_POWER GND
J 0
(3150 2925);
DISPLAY 1.170213 (3150 2925);
PAINT GREEN (3150 2925);
DISPLAY INVISIBLE (3150 2925);
FORCEADD P3V3..1
(2550 3600);
FORCEPROP 3 LASTPIN (2550 3550) SIG_NAME P3V3\g
J 0
(2560 3560);
DISPLAY 0.659574 (2560 3560);
PAINT MONO (2560 3560);
DISPLAY INVISIBLE (2560 3560);
FORCEPROP 1 LAST VOLTAGE 3.3V
J 0
(2505 3557);
DISPLAY 0.340426 (2505 3557);
PAINT SKYBLUE (2505 3557);
DISPLAY INVISIBLE (2505 3557);
FORCEPROP 2 LAST CDS_LIB mstr_symbols
J 0
(2550 3600);
PAINT ORANGE (2550 3600);
DISPLAY INVISIBLE (2550 3600);
FORCEPROP 1 LAST SIZE 1B
J 0
(2595 3622);
DISPLAY 0.446809 (2595 3622);
PAINT GREEN (2595 3622);
DISPLAY INVISIBLE (2595 3622);
FORCEPROP 1 LAST BODY_TYPE PLUMBING
J 0
(2505 3557);
DISPLAY 0.446809 (2505 3557);
PAINT GREEN (2505 3557);
DISPLAY INVISIBLE (2505 3557);
FORCEPROP 1 LAST PATH I71
J 0
(2595 3602);
DISPLAY 0.340426 (2595 3602);
PAINT GREEN (2595 3602);
DISPLAY INVISIBLE (2595 3602);
FORCEPROP 2 LAST ROOM PROCHOT_MEMHOT_ISO
J 0
(2350 3700);
DISPLAY 1.340426 (2350 3700);
PAINT ORANGE (2350 3700);
DISPLAY INVISIBLE (2350 3700);
FORCEPROP 1 LAST HDL_POWER P3V3
J 0
(2225 3475);
DISPLAY 1.170213 (2225 3475);
PAINT GREEN (2225 3475);
DISPLAY INVISIBLE (2225 3475);
FORCEADD RES..2
R 2
(2550 3375);
FORCEPROP 1 LAST LOCATION R7E11
J 2
(2505 3475);
DISPLAY 0.617021 (2505 3475);
PAINT AQUA (2505 3475);
FORCEPROP 1 LAST PART_NUMBER G21796-072
R 1
J 0
(2610 3250);
DISPLAY 0.617021 (2610 3250);
PAINT BLUE (2610 3250);
FORCEPROP 1 LAST VALUE 4.75K
J 2
(2505 3425);
DISPLAY 0.617021 (2505 3425);
PAINT SKYBLUE (2505 3425);
FORCEPROP 1 LAST TOLERANCE 1%
J 2
(2505 3375);
DISPLAY 0.617021 (2505 3375);
PAINT SKYBLUE (2505 3375);
FORCEPROP 1 LAST PACK_TYPE 0402
J 2
(2510 3275);
DISPLAY 0.617021 (2510 3275);
PAINT SKYBLUE (2510 3275);
FORCEPROP 1 LAST WATTAGE 1/16W
J 2
(2510 3325);
DISPLAY 0.617021 (2510 3325);
PAINT SKYBLUE (2510 3325);
FORCEPROP 1 LASTPIN (2550 3275) $PN 2
J 2
(2545 3285);
DISPLAY 0.617021 (2545 3285);
PAINT WHITE (2545 3285);
FORCEPROP 1 LASTPIN (2550 3475) $PN 1
J 2
(2545 3437);
DISPLAY 0.617021 (2545 3437);
PAINT WHITE (2545 3437);
FORCEPROP 1 LAST MATERIAL CHIP
J 2
(2510 3300);
PAINT SKYBLUE (2510 3300);
DISPLAY INVISIBLE (2510 3300);
FORCEPROP 2 LAST CDS_LIB mstr_discrete
J 2
(2550 3375);
DISPLAY 1.340426 (2550 3375);
PAINT ORANGE (2550 3375);
DISPLAY INVISIBLE (2550 3375);
FORCEPROP 2 LAST BOM_COST PROC_SIDEBAND
J 2
(2550 3375);
PAINT MONO (2550 3375);
DISPLAY INVISIBLE (2550 3375);
FORCEPROP 2 LAST CDS_SEC 1
J 1
(2500 3600);
PAINT MONO (2500 3600);
DISPLAY INVISIBLE (2500 3600);
FORCEPROP 2 LAST $SEC 1
J 1
(2500 3600);
PAINT MONO (2500 3600);
DISPLAY INVISIBLE (2500 3600);
FORCEPROP 2 LAST CDS_LOCATION R7E11
J 2
(2505 3475);
DISPLAY 0.617021 (2505 3475);
PAINT AQUA (2505 3475);
DISPLAY INVISIBLE (2505 3475);
FORCEPROP 1 LAST PATH I72
J 2
(2500 3550);
DISPLAY 0.978723 (2500 3550);
PAINT WHITE (2500 3550);
DISPLAY INVISIBLE (2500 3550);
FORCEPROP 2 LAST ROOM HOT_EVENTS
J 2
(2500 3550);
PAINT PEACH (2500 3550);
DISPLAY INVISIBLE (2500 3550);
FORCEADD GND..1
(2550 2575);
FORCEPROP 3 LASTPIN (2550 2625) SIG_NAME GND\g
J 0
(2560 2635);
DISPLAY 0.659574 (2560 2635);
PAINT MONO (2560 2635);
DISPLAY INVISIBLE (2560 2635);
FORCEPROP 1 LAST VOLTAGE 0.0V
J 0
(2505 2532);
DISPLAY 0.340426 (2505 2532);
PAINT SKYBLUE (2505 2532);
DISPLAY INVISIBLE (2505 2532);
FORCEPROP 2 LAST CDS_LIB mstr_symbols
J 0
(2550 2575);
PAINT ORANGE (2550 2575);
DISPLAY INVISIBLE (2550 2575);
FORCEPROP 1 LAST SIZE 1B
J 0
(2625 2525);
DISPLAY 1.170213 (2625 2525);
PAINT GREEN (2625 2525);
DISPLAY INVISIBLE (2625 2525);
FORCEPROP 1 LAST BODY_TYPE PLUMBING
J 0
(2505 2532);
DISPLAY 0.340426 (2505 2532);
PAINT GREEN (2505 2532);
DISPLAY INVISIBLE (2505 2532);
FORCEPROP 1 LAST PATH I73
J 0
(2625 2575);
DISPLAY 0.872340 (2625 2575);
PAINT AQUA (2625 2575);
DISPLAY INVISIBLE (2625 2575);
FORCEPROP 2 LAST ROOM PROCHOT_MEMHOT_ISO
J 0
(2175 2650);
PAINT ORANGE (2175 2650);
DISPLAY INVISIBLE (2175 2650);
FORCEPROP 1 LAST HDL_POWER GND
J 0
(2550 2725);
DISPLAY 1.170213 (2550 2725);
PAINT GREEN (2550 2725);
DISPLAY INVISIBLE (2550 2725);
FORCEADD OFFPAGE..1
(550 2725);
FORCEPROP 2 LAST $XR0 206 
J 0
(298 2725);
DISPLAY 0.638298 (298 2725);
PAINT MONO (298 2725);
FORCEPROP 2 LAST $XR1 120 
J 0
(178 2725);
DISPLAY 0.638298 (178 2725);
PAINT MONO (178 2725);
FORCEPROP 2 LAST $XR2 145 
J 0
(58 2725);
DISPLAY 0.638298 (58 2725);
PAINT MONO (58 2725);
FORCEPROP 2 LAST ROOM PROCHOT_MEMHOT_ISO
J 0
(300 2775);
DISPLAY 0.978723 (300 2775);
PAINT ORANGE (300 2775);
DISPLAY INVISIBLE (300 2775);
FORCEPROP 2 LAST CDS_LIB mstr_standard
J 0
(550 2725);
DISPLAY 1.340426 (550 2725);
PAINT ORANGE (550 2725);
DISPLAY INVISIBLE (550 2725);
FORCEPROP 1 LAST OFFPAGE TRUE
J 0
(875 2600);
DISPLAY 0.978723 (875 2600);
PAINT GREEN (875 2600);
DISPLAY INVISIBLE (875 2600);
FORCEPROP 1 LAST COMMENT_BODY TRUE
J 0
(675 2625);
DISPLAY 0.978723 (675 2625);
PAINT PEACH (675 2625);
DISPLAY INVISIBLE (675 2625);
FORCEPROP 2 LAST PATH I76
J 0
(250 2775);
DISPLAY 1.021277 (250 2775);
PAINT ORANGE (250 2775);
DISPLAY INVISIBLE (250 2775);
FORCEADD OFFPAGE..1
(550 2825);
FORCEPROP 2 LAST $XR0 206 
J 0
(298 2825);
DISPLAY 0.638298 (298 2825);
PAINT MONO (298 2825);
FORCEPROP 2 LAST CDS_LIB mstr_standard
J 0
(550 2825);
DISPLAY 1.340426 (550 2825);
PAINT ORANGE (550 2825);
DISPLAY INVISIBLE (550 2825);
FORCEPROP 2 LAST ROOM PROCHOT_MEMHOT_ISO
J 0
(300 2875);
DISPLAY 0.978723 (300 2875);
PAINT ORANGE (300 2875);
DISPLAY INVISIBLE (300 2875);
FORCEPROP 1 LAST OFFPAGE TRUE
J 0
(875 2700);
DISPLAY 0.978723 (875 2700);
PAINT GREEN (875 2700);
DISPLAY INVISIBLE (875 2700);
FORCEPROP 1 LAST COMMENT_BODY TRUE
J 0
(675 2725);
DISPLAY 0.978723 (675 2725);
PAINT PEACH (675 2725);
DISPLAY INVISIBLE (675 2725);
FORCEPROP 2 LAST PATH I77
J 0
(250 2875);
DISPLAY 1.021277 (250 2875);
PAINT ORANGE (250 2875);
DISPLAY INVISIBLE (250 2875);
FORCEADD CAP_A..1
(700 4775);
FORCEPROP 1 LAST LOCATION C7E3
J 0
(750 4875);
DISPLAY 0.617021 (750 4875);
PAINT AQUA (750 4875);
FORCEPROP 1 LAST PART_NUMBER A36096-030
J 0
(750 4625);
DISPLAY 0.617021 (750 4625);
PAINT BLUE (750 4625);
FORCEPROP 1 LAST VALUE 0.1UF
J 0
(750 4825);
DISPLAY 0.617021 (750 4825);
PAINT SKYBLUE (750 4825);
FORCEPROP 1 LAST TOLERANCE 10%
J 0
(750 4725);
DISPLAY 0.617021 (750 4725);
PAINT SKYBLUE (750 4725);
FORCEPROP 1 LAST PACK_TYPE 0402V
J 0
(750 4575);
DISPLAY 0.617021 (750 4575);
PAINT SKYBLUE (750 4575);
FORCEPROP 1 LAST VOLTAGE 16V
J 0
(750 4775);
DISPLAY 0.617021 (750 4775);
PAINT SKYBLUE (750 4775);
FORCEPROP 1 LAST MATERIAL X7R
J 0
(750 4675);
DISPLAY 0.617021 (750 4675);
PAINT SKYBLUE (750 4675);
FORCEPROP 1 LASTPIN (700 4875) $PN 1
J 0
(710 4855);
DISPLAY 0.617021 (710 4855);
PAINT ORANGE (710 4855);
FORCEPROP 1 LASTPIN (700 4675) $PN 2
J 0
(710 4655);
DISPLAY 0.617021 (710 4655);
PAINT ORANGE (710 4655);
FORCEPROP 1 LAST PATH I92
J 0
(750 4925);
DISPLAY 0.978723 (750 4925);
PAINT WHITE (750 4925);
DISPLAY INVISIBLE (750 4925);
FORCEPROP 2 LAST ROOM PROC_SIDEBAND
J 0
(750 4925);
DISPLAY 1.021277 (750 4925);
PAINT ORANGE (750 4925);
DISPLAY INVISIBLE (750 4925);
FORCEPROP 2 LAST CDS_LOCATION C7E3
J 0
(750 4875);
DISPLAY 0.617021 (750 4875);
PAINT AQUA (750 4875);
DISPLAY INVISIBLE (750 4875);
FORCEPROP 2 LAST BOM_COST PROC_SIDEBAND
J 0
(750 4975);
DISPLAY 1.021277 (750 4975);
PAINT ORANGE (750 4975);
DISPLAY INVISIBLE (750 4975);
FORCEPROP 2 LAST CDS_LIB dev_discrete
J 0
(700 4775);
PAINT ORANGE (700 4775);
DISPLAY INVISIBLE (700 4775);
FORCEPROP 2 LAST CDS_SEC 1
J 0
(750 4925);
PAINT ORANGE (750 4925);
DISPLAY INVISIBLE (750 4925);
FORCEPROP 2 LAST SEC_TYPE 0402V
J 0
(750 4975);
DISPLAY 1.021277 (750 4975);
PAINT ORANGE (750 4975);
DISPLAY INVISIBLE (750 4975);
FORCEPROP 2 LAST SEC 1
J 0
(750 4975);
DISPLAY 0.680851 (750 4975);
PAINT MONO (750 4975);
DISPLAY INVISIBLE (750 4975);
FORCEADD GND..1
(700 4525);
FORCEPROP 3 LASTPIN (700 4575) SIG_NAME GND\g
J 0
(710 4585);
DISPLAY 0.659574 (710 4585);
PAINT MONO (710 4585);
DISPLAY INVISIBLE (710 4585);
FORCEPROP 1 LAST VOLTAGE 0.0V
J 0
(655 4482);
DISPLAY 0.340426 (655 4482);
PAINT SKYBLUE (655 4482);
DISPLAY INVISIBLE (655 4482);
FORCEPROP 2 LAST CDS_LIB mstr_symbols
J 0
(700 4525);
PAINT ORANGE (700 4525);
DISPLAY INVISIBLE (700 4525);
FORCEPROP 1 LAST SIZE 1B
J 0
(775 4475);
DISPLAY 0.872340 (775 4475);
PAINT AQUA (775 4475);
DISPLAY INVISIBLE (775 4475);
FORCEPROP 1 LAST BODY_TYPE PLUMBING
J 0
(655 4482);
DISPLAY 0.340426 (655 4482);
PAINT GREEN (655 4482);
DISPLAY INVISIBLE (655 4482);
FORCEPROP 1 LAST PATH I94
J 0
(775 4525);
DISPLAY 0.872340 (775 4525);
PAINT AQUA (775 4525);
DISPLAY INVISIBLE (775 4525);
FORCEPROP 1 LAST HDL_POWER GND
J 0
(700 4675);
DISPLAY 0.872340 (700 4675);
PAINT GREEN (700 4675);
DISPLAY INVISIBLE (700 4675);
FORCEADD P3V3_STBY..1
(700 5000);
FORCEPROP 3 LASTPIN (700 4950) SIG_NAME P3V3_STBY\g
J 0
(710 4960);
DISPLAY 0.659574 (710 4960);
PAINT MONO (710 4960);
DISPLAY INVISIBLE (710 4960);
FORCEPROP 1 LAST VOLTAGE 3.3V
J 0
(655 4957);
DISPLAY 0.340426 (655 4957);
PAINT SKYBLUE (655 4957);
DISPLAY INVISIBLE (655 4957);
FORCEPROP 2 LAST CDS_LIB mstr_symbols
J 0
(700 5000);
PAINT ORANGE (700 5000);
DISPLAY INVISIBLE (700 5000);
FORCEPROP 1 LAST SIZE 1B
J 0
(745 5022);
DISPLAY 0.340426 (745 5022);
PAINT GREEN (745 5022);
DISPLAY INVISIBLE (745 5022);
FORCEPROP 1 LAST BODY_TYPE PLUMBING
J 0
(655 4957);
DISPLAY 0.340426 (655 4957);
PAINT GREEN (655 4957);
DISPLAY INVISIBLE (655 4957);
FORCEPROP 1 LAST PATH I98
J 0
(745 5002);
DISPLAY 0.340426 (745 5002);
PAINT GREEN (745 5002);
DISPLAY INVISIBLE (745 5002);
FORCEPROP 1 LAST HDL_POWER P3V3_STBY
J 0
(400 4875);
DISPLAY 0.872340 (400 4875);
PAINT ORANGE (400 4875);
DISPLAY INVISIBLE (400 4875);
FORCEADD CAD_NOTE..1
(1225 4825);
FORCEPROP 0 LAST L2 U7E2
J 0
(1075 4625);
DISPLAY 1.021277 (1075 4625);
PAINT ORANGE (1075 4625);
FORCEPROP 0 LAST L1 PLACE CAP CLOSE TO
J 0
(1075 4675);
DISPLAY 1.021277 (1075 4675);
PAINT ORANGE (1075 4675);
FORCEPROP 2 LAST CDS_LIB mstr_symbols
J 0
(1225 4825);
PAINT ORANGE (1225 4825);
DISPLAY INVISIBLE (1225 4825);
FORCEPROP 1 LAST COMMENT_BODY TRUE
J 0
(1250 4925);
DISPLAY 0.978723 (1250 4925);
PAINT ORANGE (1250 4925);
DISPLAY INVISIBLE (1250 4925);
FORCEADD CAD_NOTE..1
(1575 3550);
FORCEPROP 0 LAST L2 U7E3
J 0
(1425 3350);
DISPLAY 1.021277 (1425 3350);
PAINT ORANGE (1425 3350);
FORCEPROP 0 LAST L1 PLACE CAP CLOSE TO
J 0
(1425 3400);
DISPLAY 1.021277 (1425 3400);
PAINT ORANGE (1425 3400);
FORCEPROP 2 LAST CDS_LIB mstr_symbols
J 0
(1575 3550);
PAINT ORANGE (1575 3550);
DISPLAY INVISIBLE (1575 3550);
FORCEPROP 1 LAST COMMENT_BODY TRUE
J 0
(1600 3650);
DISPLAY 0.978723 (1600 3650);
PAINT ORANGE (1600 3650);
DISPLAY INVISIBLE (1600 3650);
FORCEADD INTEL_CORP_BPAGE..1
(4250 200);
FORCEPROP 1 LAST CDS_CON_LAST_MODIFIED Tue Dec 01 11:51:49 2015
J 0
(2825 525);
PAINT ORANGE (2825 525);
DISPLAY INVISIBLE (2825 525);
FORCEPROP 1 LAST CUSTOM_TXT_CDS <CURRENT_DESIGN_SHEET> OF <TOTAL_DESIGN_SHEETS>
J 0
(3750 225);
PAINT GREEN (3750 225);
FORCEPROP 1 LAST CUSTOM_TXT_CDS <CON_LAST_MODIFIED>
J 0
(2325 550);
PAINT GREEN (2325 550);
FORCEPROP 2 LAST CUSTOM_TXT_CDS <XR_PAGE_TITLE>
J 0
(-3640 5450);
DISPLAY 0.638298 (-3640 5450);
PAINT PINK (-3640 5450);
DISPLAY INVISIBLE (-3640 5450);
FORCEPROP 1 LAST SCH_ADDRESS3 Santa Clara, CA 95052-8119
J 0
(275 225);
DISPLAY 0.617021 (275 225);
PAINT GREEN (275 225);
FORCEPROP 1 LAST SCH_ADDRESS2 P.O. BOX 58119
J 0
(275 275);
DISPLAY 0.617021 (275 275);
PAINT GREEN (275 275);
FORCEPROP 1 LAST SCH_ADDRESS1 2200 Mission College Blvd.
J 0
(275 325);
DISPLAY 0.617021 (275 325);
PAINT GREEN (275 325);
FORCEPROP 1 LAST SCH_TITLE CPU SIDE BAND: PROCHOT & MEMHOT (2/2)
J 0
(-3700 250);
DISPLAY 1.212766 (-3700 250);
PAINT ORANGE (-3700 250);
FORCEPROP 1 LAST SCH_NUMBER H4694802
J 0
(2950 350);
DISPLAY 1.212766 (2950 350);
PAINT YELLOW (2950 350);
FORCEPROP 1 LAST SCH_DEPT BESD
J 1
(-200 300);
DISPLAY 1.212766 (-200 300);
PAINT YELLOW (-200 300);
FORCEPROP 1 LAST SCH_REV 2.420
J 0
(4000 350);
DISPLAY 0.978723 (4000 350);
PAINT YELLOW (4000 350);
FORCEPROP 2 LAST CDS_LIB mstr_symbols
J 0
(4250 200);
PAINT MONO (4250 200);
DISPLAY INVISIBLE (4250 200);
FORCEPROP 2 LAST PAGE_BORDER TRUE
J 0
(-3640 5450);
DISPLAY 0.638298 (-3640 5450);
PAINT PINK (-3640 5450);
DISPLAY INVISIBLE (-3640 5450);
FORCEPROP 1 LAST COMMENT_BODY TRUE
J 0
(4262 212);
DISPLAY 0.468085 (4262 212);
PAINT GREEN (4262 212);
DISPLAY INVISIBLE (4262 212);
FORCEPROP 2 LAST CDS_XR_PAGE_TITLE CR-95 : @BASEBOARD_FAB2_LIB.BASEBOARD_FAB2(SCH_1):PAGE95
J 0
(-3640 5450);
DISPLAY 0.638298 (-3640 5450);
PAINT PINK (-3640 5450);
DISPLAY INVISIBLE (-3640 5450);
WIRE 16 -1 (-3100 500)(-3100 475);
WIRE 16 -1 (2150 1150)(2150 1000);
WIRE 16 -1 (2150 1900)(2150 2025);
WIRE 16 -1 (1125 3625)(1125 3550);
WIRE 16 -1 (1125 3350)(1125 3250);
WIRE 16 -1 (-3100 4300)(-3100 4350);
WIRE 16 -1 (-3100 3750)(-3100 3725);
WIRE 16 -1 (-3100 3075)(-3100 3050);
WIRE 16 -1 (-3100 2425)(-3100 2400);
WIRE 16 -1 (-3100 1750)(-3100 1725);
WIRE 16 -1 (-3100 1100)(-3100 1075);
WIRE 16 -1 (3050 4275)(3050 4525);
WIRE 16 -1 (2475 5000)(2475 4900);
WIRE 16 -1 (2475 4125)(2475 4075);
WIRE 16 -1 (3150 3075)(3150 2825);
WIRE 16 -1 (2550 3550)(2550 3475);
WIRE 16 -1 (2550 2675)(2550 2625);
WIRE 16 -1 (700 4675)(700 4575);
WIRE 16 -1 (700 4950)(700 4875);
WIRE 16 -1 (-3100 4850)(-750 4850);
FORCEPROP 0 LAST SIG_NAME FM_PWRBRK_N
J 0
(-1285 4860);
DISPLAY 0.617021 (-1285 4860);
PAINT ORANGE (-1285 4860);
WIRE 16 -1 (-3100 4750)(-3100 4850);
WIRE 16 -1 (-3425 5025)(-2525 5025);
FORCEPROP 2 LAST SIG_NAME FM_SYS_THROTTLE_LVC3
J 0
(-3110 5035);
DISPLAY 0.617021 (-3110 5035);
PAINT ORANGE (-3110 5035);
WIRE 16 -1 (-3425 4450)(-3425 5025);
WIRE 16 -1 (-3300 4450)(-3425 4450);
WIRE 16 -1 (-3425 3850)(-3425 4450);
WIRE 16 -1 (-3300 3850)(-3425 3850);
WIRE 16 -1 (-3425 3175)(-3425 3850);
WIRE 16 -1 (-3425 3175)(-3300 3175);
WIRE 16 -1 (-3425 2525)(-3425 3175);
WIRE 16 -1 (-3425 2525)(-3300 2525);
WIRE 16 -1 (-3425 1850)(-3425 2525);
WIRE 16 -1 (-3300 1850)(-3425 1850);
WIRE 16 -1 (-3425 1850)(-3425 1200);
WIRE 16 -1 (-3300 1200)(-3425 1200);
WIRE 16 -1 (-3425 600)(-3425 1200);
WIRE 16 -1 (-3425 600)(-3300 600);
WIRE 16 -1 (-750 3525)(-3100 3525);
FORCEPROP 2 LAST SIG_NAME H_CPU1_PROCHOT_G_N
J 0
(-1300 3535);
DISPLAY 0.617021 (-1300 3535);
PAINT ORANGE (-1300 3535);
WIRE 16 -1 (-3100 3475)(-3100 3525);
WIRE 16 -1 (-3100 2850)(-750 2850);
FORCEPROP 2 LAST SIG_NAME H_CPU0_MEMABC_MEMHOT_G_N
J 0
(-1450 2860);
DISPLAY 0.617021 (-1450 2860);
PAINT ORANGE (-1450 2860);
WIRE 16 -1 (-3100 2825)(-3100 2850);
WIRE 16 -1 (-3100 2200)(-725 2200);
FORCEPROP 2 LAST SIG_NAME H_CPU0_MEMDEF_MEMHOT_G_N
J 0
(-1425 2210);
DISPLAY 0.617021 (-1425 2210);
PAINT ORANGE (-1425 2210);
WIRE 16 -1 (-3100 2200)(-3100 2150);
WIRE 16 -1 (-3100 1550)(-725 1550);
FORCEPROP 2 LAST SIG_NAME H_CPU1_MEMGHJ_MEMHOT_G_N
J 0
(-1450 1560);
DISPLAY 0.617021 (-1450 1560);
PAINT ORANGE (-1450 1560);
WIRE 16 -1 (-3100 1500)(-3100 1550);
WIRE 16 -1 (-3100 925)(-725 925);
FORCEPROP 2 LAST SIG_NAME H_CPU1_MEMKLM_MEMHOT_G_N
J 0
(-1425 935);
DISPLAY 0.617021 (-1425 935);
PAINT ORANGE (-1425 935);
WIRE 16 -1 (-3100 900)(-3100 925);
WIRE 16 -1 (-750 4200)(-3100 4200);
FORCEPROP 2 LAST SIG_NAME H_CPU0_PROCHOT_G_N
J 0
(-1300 4210);
DISPLAY 0.617021 (-1300 4210);
PAINT ORANGE (-1300 4210);
WIRE 16 -1 (-3100 4200)(-3100 4150);
WIRE 16 2175 (0 575)(0 5125);
WIRE 16 -1 (1225 1250)(750 1250);
FORCEPROP 0 LAST SIG_NAME FM_THROTTLE_N
J 0
(765 1260);
DISPLAY 0.617021 (765 1260);
PAINT ORANGE (765 1260);
WIRE 16 -1 (1950 1250)(1425 1250);
FORCEPROP 0 LAST SIG_NAME FM_THROTTLE_R_N
J 0
(1465 1260);
DISPLAY 0.617021 (1465 1260);
PAINT ORANGE (1465 1260);
FORCEPROP 2 LASTPROP $XRERR UNIQUE?
J 0
(1225 1260);
DISPLAY 0.638298 (1225 1260);
PAINT MONO (1225 1260);
DISPLAY INVISIBLE (1225 1260);
WIRE 16 -1 (600 2725)(1425 2725);
FORCEPROP 0 LAST SIG_NAME IRQ_PVCCIN_CPU1_VRHOT_LVC3_N
J 0
(575 2735);
DISPLAY 0.617021 (575 2735);
PAINT ORANGE (575 2735);
WIRE 16 -1 (600 2825)(1425 2825);
FORCEPROP 0 LAST SIG_NAME FM_PVCCIN_CPU1_PWR_IN_ALERT_N
J 0
(575 2840);
DISPLAY 0.617021 (575 2840);
PAINT ORANGE (575 2840);
WIRE 16 -1 (2350 2775)(1725 2775);
FORCEPROP 0 LAST SIG_NAME IRQ_CPU1_PROCHOT_G_N
J 0
(1765 2785);
DISPLAY 0.617021 (1765 2785);
PAINT ORANGE (1765 2785);
FORCEPROP 2 LASTPROP $XRERR UNIQUE?
J 0
(1525 2785);
DISPLAY 0.638298 (1525 2785);
PAINT MONO (1525 2785);
DISPLAY INVISIBLE (1525 2785);
WIRE 16 682 (4050 3875)(125 3875);
WIRE 16 682 (4075 2350)(100 2350);
WIRE 16 -1 (2150 1700)(2150 1600);
WIRE 16 -1 (2150 1600)(3205 1600);
FORCEPROP 2 LAST SIG_NAME FM_SYS_THROTTLE_LVC3
J 0
(2590 1610);
DISPLAY 0.617021 (2590 1610);
PAINT ORANGE (2590 1610);
WIRE 16 -1 (2150 1600)(2150 1550);
WIRE 16 -1 (2550 3075)(2550 3175);
WIRE 16 -1 (2950 3175)(2550 3175);
FORCEPROP 0 LAST SIG_NAME IRQ_CPU1_VRHOT
J 0
(2615 3185);
DISPLAY 0.617021 (2615 3185);
PAINT ORANGE (2615 3185);
FORCEPROP 2 LASTPROP $XRERR UNIQUE?
J 0
(2375 3185);
DISPLAY 0.638298 (2375 3185);
PAINT MONO (2375 3185);
DISPLAY INVISIBLE (2375 3185);
WIRE 16 -1 (2550 3275)(2550 3175);
WIRE 16 -1 (3705 3575)(3150 3575);
FORCEPROP 0 LAST SIG_NAME H_CPU1_PROCHOT_G_N
J 0
(3150 3585);
DISPLAY 0.617021 (3150 3585);
PAINT ORANGE (3150 3585);
WIRE 16 -1 (3150 3475)(3150 3575);
WIRE 16 -1 (550 4175)(1400 4175);
FORCEPROP 0 LAST SIG_NAME IRQ_PVCCIN_CPU0_VRHOT_LVC3_N
J 0
(525 4185);
DISPLAY 0.617021 (525 4185);
PAINT ORANGE (525 4185);
WIRE 16 -1 (550 4275)(1400 4275);
FORCEPROP 0 LAST SIG_NAME FM_PVCCIN_CPU0_PWR_IN_ALERT_N
J 0
(525 4290);
DISPLAY 0.617021 (525 4290);
PAINT ORANGE (525 4290);
WIRE 16 -1 (2275 4225)(1700 4225);
FORCEPROP 0 LAST SIG_NAME IRQ_CPU0_PROCHOT_G_N
J 0
(1740 4235);
DISPLAY 0.617021 (1740 4235);
PAINT ORANGE (1740 4235);
FORCEPROP 2 LASTPROP $XRERR UNIQUE?
J 0
(1500 4235);
DISPLAY 0.638298 (1500 4235);
PAINT MONO (1500 4235);
DISPLAY INVISIBLE (1500 4235);
WIRE 16 -1 (2475 4700)(2475 4625);
WIRE 16 -1 (2850 4625)(2475 4625);
FORCEPROP 0 LAST SIG_NAME IRQ_CPU0_VRHOT
J 0
(2515 4635);
DISPLAY 0.617021 (2515 4635);
PAINT ORANGE (2515 4635);
FORCEPROP 2 LASTPROP $XRERR UNIQUE?
J 0
(2275 4635);
DISPLAY 0.638298 (2275 4635);
PAINT MONO (2275 4635);
DISPLAY INVISIBLE (2275 4635);
WIRE 16 -1 (2475 4525)(2475 4625);
WIRE 16 -1 (3605 5025)(3050 5025);
FORCEPROP 0 LAST SIG_NAME H_CPU0_PROCHOT_G_N
J 0
(3050 5035);
DISPLAY 0.617021 (3050 5035);
PAINT ORANGE (3050 5035);
WIRE 16 -1 (3050 4925)(3050 5025);
DOT 1 (-3425 4450);
DOT 1 (-3425 1200);
DOT 1 (-3425 1850);
DOT 1 (-3425 2525);
DOT 1 (-3425 3175);
DOT 1 (-3425 3850);
DOT 1 (2550 3175);
DOT 1 (2475 4625);
DOT 1 (2150 1600);
FORCENOTE
ROOM=PROC_SIDEBAND
(-2812 358) 0;
DISPLAY LEFT (-2812 358);
DISPLAY 1.595745 (-2812 358);
PAINT PURPLE (-2812 358);
QUIT
